FILE_TYPE = MACRO_DRAWING;
SET COLOR_WIRE YELLOW;
SET COLOR_PROP ORANGE;
SET COLOR_DOT WHITE;
SET COLOR_ARC YELLOW;
SET COLOR_BODY GREEN;
SET COLOR_NOTE PURPLE;
SET PROP_DISPLAY VALUE;
SET PAGE_NUMBER P524;
FORCEADD GND_SG..1
(-12250 8600);
FORCEPROP 3 LASTPIN (-12200 8650) SIG_NAME SG\g
J 0
(-12190 8660);
DISPLAY 0.659574 (-12190 8660);
PAINT MONO (-12190 8660);
DISPLAY INVISIBLE (-12190 8660);
FORCEPROP 1 LAST HDL_POWER SG
J 1
(-12195 8505);
DISPLAY 0.808511 (-12195 8505);
PAINT GREEN (-12195 8505);
FORCEPROP 2 LAST CDS_LIB cls
J 0
(-12250 8600);
DISPLAY INVISIBLE (-12250 8600);
FORCEPROP 1 LAST CDS_LMAN_SYM_OUTLINE 0,0,100,-50
J 0
(-12250 8600);
DISPLAY 0.468085 (-12250 8600);
PAINT GREEN (-12250 8600);
DISPLAY INVISIBLE (-12250 8600);
FORCEPROP 1 LAST PATH I1
J 0
(-12215 8600);
DISPLAY 0.808511 (-12215 8600);
PAINT GREEN (-12215 8600);
DISPLAY INVISIBLE (-12215 8600);
FORCEPROP 1 LAST BODY_TYPE PLUMBING
J 0
(-12235 8585);
DISPLAY 0.808511 (-12235 8585);
PAINT GREEN (-12235 8585);
DISPLAY INVISIBLE (-12235 8585);
FORCEADD CAPACITOR..1
R 1
(-9650 7600);
FORCEPROP 1 LAST $LOCATION C87
J 2
(-9400 7550);
DISPLAY 1.212766 (-9400 7550);
PAINT GREEN (-9400 7550);
FORCEPROP 0 LAST CDS_LOCATION C87
R 1
J 0
(-9550 7750);
DISPLAY 1.021277 (-9550 7750);
DISPLAY INVISIBLE (-9550 7750);
FORCEPROP 0 LAST $SEC 1
R 1
J 0
(-9550 7750);
DISPLAY 0.680851 (-9550 7750);
PAINT MONO (-9550 7750);
DISPLAY INVISIBLE (-9550 7750);
FORCEPROP 0 LAST CDS_SEC 1
R 1
J 0
(-9550 7750);
DISPLAY 1.021277 (-9550 7750);
DISPLAY INVISIBLE (-9550 7750);
FORCEPROP 0 LASTPIN (-9650 7500) $PN 1
R 1
J 2
(-9660 7490);
DISPLAY 0.680851 (-9660 7490);
PAINT MONO (-9660 7490);
FORCEPROP 0 LASTPIN (-9650 7750) $PN 2
R 1
J 0
(-9660 7760);
DISPLAY 0.680851 (-9660 7760);
PAINT MONO (-9660 7760);
FORCEPROP 1 LAST VALUE 18PF
J 0
(-9550 7650);
DISPLAY 1.212766 (-9550 7650);
PAINT GREEN (-9550 7650);
FORCEPROP 0 LAST PACKAGE 0201
J 0
(-9550 7750);
DISPLAY 1.021277 (-9550 7750);
FORCEPROP 1 LAST CLS_PN G104-0A180-FJ
R 1
J 2
(-9750 7550);
DISPLAY 1.212766 (-9750 7550);
PAINT GREEN (-9750 7550);
DISPLAY INVISIBLE (-9750 7550);
FORCEPROP 1 LAST PATH I10
R 1
J 2
(-9750 7550);
DISPLAY 1.212766 (-9750 7550);
PAINT GREEN (-9750 7550);
DISPLAY INVISIBLE (-9750 7550);
FORCEPROP 2 LASTPIN (-9650 7750) SIG_NAME UN$524$CAPACITOR$I10$2
J 0
(-9640 7760);
DISPLAY 0.659574 (-9640 7760);
PAINT MONO (-9640 7760);
DISPLAY INVISIBLE (-9640 7760);
FORCEPROP 1 LAST TOLERANCE 5%
R 1
J 2
(-9750 7500);
DISPLAY 1.212766 (-9750 7500);
PAINT GREEN (-9750 7500);
DISPLAY INVISIBLE (-9750 7500);
FORCEPROP 1 LAST CDS_LMAN_SYM_OUTLINE 0,50,50,-50
R 1
J 0
(-9650 7600);
DISPLAY 0.468085 (-9650 7600);
PAINT GREEN (-9650 7600);
DISPLAY INVISIBLE (-9650 7600);
FORCEPROP 2 LAST CDS_LIB passive
J 0
(-9650 7600);
DISPLAY INVISIBLE (-9650 7600);
FORCEADD GND_SG..1
(-10950 11250);
FORCEPROP 3 LASTPIN (-10900 11300) SIG_NAME SG\g
J 0
(-10890 11310);
DISPLAY 0.659574 (-10890 11310);
PAINT MONO (-10890 11310);
DISPLAY INVISIBLE (-10890 11310);
FORCEPROP 1 LAST HDL_POWER SG
J 1
(-10895 11155);
DISPLAY 0.808511 (-10895 11155);
PAINT GREEN (-10895 11155);
FORCEPROP 1 LAST PATH I102
J 0
(-10915 11250);
DISPLAY 0.808511 (-10915 11250);
PAINT GREEN (-10915 11250);
DISPLAY INVISIBLE (-10915 11250);
FORCEPROP 1 LAST BODY_TYPE PLUMBING
J 0
(-10935 11235);
DISPLAY 0.808511 (-10935 11235);
PAINT GREEN (-10935 11235);
DISPLAY INVISIBLE (-10935 11235);
FORCEPROP 2 LAST CDS_LIB cls
J 0
(-10950 11250);
DISPLAY INVISIBLE (-10950 11250);
FORCEPROP 1 LAST CDS_LMAN_SYM_OUTLINE 0,0,100,-50
J 0
(-10950 11250);
DISPLAY 0.468085 (-10950 11250);
PAINT GREEN (-10950 11250);
DISPLAY INVISIBLE (-10950 11250);
FORCEADD RESISTOR..2
(-8350 8150);
FORCEPROP 1 LAST $LOCATION R463
J 0
(-8700 8150);
DISPLAY 1.212766 (-8700 8150);
PAINT GREEN (-8700 8150);
FORCEPROP 0 LAST CDS_LOCATION R463
J 0
(-8700 8300);
DISPLAY 1.021277 (-8700 8300);
DISPLAY INVISIBLE (-8700 8300);
FORCEPROP 0 LAST $SEC 1
J 0
(-8700 8300);
DISPLAY 0.680851 (-8700 8300);
PAINT MONO (-8700 8300);
DISPLAY INVISIBLE (-8700 8300);
FORCEPROP 0 LAST CDS_SEC 1
J 0
(-8700 8300);
DISPLAY 1.021277 (-8700 8300);
DISPLAY INVISIBLE (-8700 8300);
FORCEPROP 0 LASTPIN (-8350 8250) $PN 1
R 1
J 0
(-8360 8260);
DISPLAY 0.680851 (-8360 8260);
PAINT MONO (-8360 8260);
FORCEPROP 0 LASTPIN (-8350 8000) $PN 2
R 1
J 2
(-8360 7990);
DISPLAY 0.680851 (-8360 7990);
PAINT MONO (-8360 7990);
FORCEPROP 1 LAST VALUE 12KOHM
J 0
(-8750 8050);
DISPLAY 1.212766 (-8750 8050);
PAINT GREEN (-8750 8050);
FORCEPROP 0 LAST PACKAGE 0402
J 0
(-8700 8250);
DISPLAY 1.021277 (-8700 8250);
FORCEPROP 1 LAST PATH I106
J 0
(-8547 8255);
DISPLAY 1.212766 (-8547 8255);
PAINT GREEN (-8547 8255);
DISPLAY INVISIBLE (-8547 8255);
FORCEPROP 1 LAST TOLERANCE 1%
J 0
(-8547 8405);
DISPLAY 1.212766 (-8547 8405);
PAINT GREEN (-8547 8405);
DISPLAY INVISIBLE (-8547 8405);
FORCEPROP 2 LAST CDS_LIB passive
J 0
(-8350 8150);
DISPLAY INVISIBLE (-8350 8150);
FORCEPROP 1 LAST CDS_LMAN_SYM_OUTLINE -50,50,50,-100
J 0
(-8350 8150);
DISPLAY 0.468085 (-8350 8150);
PAINT GREEN (-8350 8150);
DISPLAY INVISIBLE (-8350 8150);
FORCEPROP 1 LAST CLS_PN G155-01202-01
J 0
(-8486 8350);
DISPLAY 1.212766 (-8486 8350);
PAINT GREEN (-8486 8350);
DISPLAY INVISIBLE (-8486 8350);
FORCEADD FERRITEBEAD..1
(-10050 11100);
FORCEPROP 1 LAST $LOCATION L22
J 2
(-10110 11159);
DISPLAY 1.212766 (-10110 11159);
PAINT GREEN (-10110 11159);
FORCEPROP 0 LAST CDS_LOCATION L22
J 0
(-10100 11250);
DISPLAY 1.021277 (-10100 11250);
DISPLAY INVISIBLE (-10100 11250);
FORCEPROP 0 LAST $SEC 1
J 0
(-10100 11250);
DISPLAY 0.680851 (-10100 11250);
PAINT MONO (-10100 11250);
DISPLAY INVISIBLE (-10100 11250);
FORCEPROP 0 LAST CDS_SEC 1
J 0
(-10100 11250);
DISPLAY 1.021277 (-10100 11250);
DISPLAY INVISIBLE (-10100 11250);
FORCEPROP 0 LASTPIN (-10150 11050) $PN 1
J 2
(-10160 11060);
DISPLAY 0.680851 (-10160 11060);
PAINT MONO (-10160 11060);
FORCEPROP 0 LASTPIN (-9750 11050) $PN 2
J 0
(-9740 11060);
DISPLAY 0.680851 (-9740 11060);
PAINT MONO (-9740 11060);
FORCEPROP 1 LAST VALUE 600OHM
J 0
(-9650 11100);
DISPLAY 1.212766 (-9650 11100);
PAINT GREEN (-9650 11100);
FORCEPROP 0 LAST DCR 1300MA 0.15OHM
J 0
(-10250 10950);
FORCEPROP 0 LAST PACKAGE 0603
J 0
(-10050 11150);
DISPLAY 1.021277 (-10050 11150);
FORCEPROP 2 LAST CDS_LIB passive
J 0
(-10050 11100);
DISPLAY INVISIBLE (-10050 11100);
FORCEPROP 1 LAST CDS_LMAN_SYM_OUTLINE 0,0,200,-100
J 0
(-10050 11100);
DISPLAY 0.468085 (-10050 11100);
PAINT GREEN (-10050 11100);
DISPLAY INVISIBLE (-10050 11100);
FORCEPROP 1 LAST CLS_PN G191-10097-01
J 2
(-10100 11150);
DISPLAY 1.212766 (-10100 11150);
PAINT GREEN (-10100 11150);
DISPLAY INVISIBLE (-10100 11150);
FORCEPROP 1 LAST PATH I118
J 2
(-10100 11150);
DISPLAY 1.212766 (-10100 11150);
PAINT GREEN (-10100 11150);
DISPLAY INVISIBLE (-10100 11150);
FORCEPROP 1 LAST TOLERANCE 25%
J 0
(-10150 11150);
DISPLAY 1.212766 (-10150 11150);
PAINT GREEN (-10150 11150);
DISPLAY INVISIBLE (-10150 11150);
FORCEADD GND_SG..1
(-9050 11300);
FORCEPROP 3 LASTPIN (-9000 11350) SIG_NAME SG\g
J 0
(-8990 11360);
DISPLAY 0.659574 (-8990 11360);
PAINT MONO (-8990 11360);
DISPLAY INVISIBLE (-8990 11360);
FORCEPROP 1 LAST HDL_POWER SG
J 1
(-8995 11205);
DISPLAY 0.808511 (-8995 11205);
PAINT GREEN (-8995 11205);
FORCEPROP 1 LAST PATH I119
J 0
(-9015 11300);
DISPLAY 0.808511 (-9015 11300);
PAINT GREEN (-9015 11300);
DISPLAY INVISIBLE (-9015 11300);
FORCEPROP 1 LAST BODY_TYPE PLUMBING
J 0
(-9035 11285);
DISPLAY 0.808511 (-9035 11285);
PAINT GREEN (-9035 11285);
DISPLAY INVISIBLE (-9035 11285);
FORCEPROP 2 LAST CDS_LIB cls
J 0
(-9050 11300);
DISPLAY INVISIBLE (-9050 11300);
FORCEPROP 1 LAST CDS_LMAN_SYM_OUTLINE 0,0,100,-50
J 0
(-9050 11300);
DISPLAY 0.468085 (-9050 11300);
PAINT GREEN (-9050 11300);
DISPLAY INVISIBLE (-9050 11300);
FORCEADD GND_SG..1
(-9050 10450);
FORCEPROP 3 LASTPIN (-9000 10500) SIG_NAME SG\g
J 0
(-8990 10510);
DISPLAY 0.659574 (-8990 10510);
PAINT MONO (-8990 10510);
DISPLAY INVISIBLE (-8990 10510);
FORCEPROP 1 LAST HDL_POWER SG
J 1
(-8995 10355);
DISPLAY 0.808511 (-8995 10355);
PAINT GREEN (-8995 10355);
FORCEPROP 1 LAST CDS_LMAN_SYM_OUTLINE 0,0,100,-50
J 0
(-9050 10450);
DISPLAY 0.468085 (-9050 10450);
PAINT GREEN (-9050 10450);
DISPLAY INVISIBLE (-9050 10450);
FORCEPROP 2 LAST CDS_LIB cls
J 0
(-9050 10450);
DISPLAY INVISIBLE (-9050 10450);
FORCEPROP 1 LAST BODY_TYPE PLUMBING
J 0
(-9035 10435);
DISPLAY 0.808511 (-9035 10435);
PAINT GREEN (-9035 10435);
DISPLAY INVISIBLE (-9035 10435);
FORCEPROP 1 LAST PATH I120
J 0
(-9015 10450);
DISPLAY 0.808511 (-9015 10450);
PAINT GREEN (-9015 10450);
DISPLAY INVISIBLE (-9015 10450);
FORCEADD RESISTOR..1
(-8600 9350);
FORCEPROP 1 LAST $LOCATION R460
J 2
(-8750 9350);
DISPLAY 1.212766 (-8750 9350);
PAINT GREEN (-8750 9350);
FORCEPROP 0 LAST CDS_LOCATION R460
J 0
(-8650 9450);
DISPLAY 1.021277 (-8650 9450);
DISPLAY INVISIBLE (-8650 9450);
FORCEPROP 0 LAST $SEC 1
J 0
(-8650 9450);
DISPLAY 0.680851 (-8650 9450);
PAINT MONO (-8650 9450);
DISPLAY INVISIBLE (-8650 9450);
FORCEPROP 0 LAST CDS_SEC 1
J 0
(-8650 9450);
DISPLAY 1.021277 (-8650 9450);
DISPLAY INVISIBLE (-8650 9450);
FORCEPROP 0 LASTPIN (-8700 9350) $PN 1
J 2
(-8710 9360);
DISPLAY 0.680851 (-8710 9360);
PAINT MONO (-8710 9360);
FORCEPROP 0 LASTPIN (-8450 9350) $PN 2
J 0
(-8440 9360);
DISPLAY 0.680851 (-8440 9360);
PAINT MONO (-8440 9360);
FORCEPROP 0 LAST PACKAGE 0402
J 0
(-8650 9400);
DISPLAY 1.021277 (-8650 9400);
FORCEPROP 1 LAST VALUE 1KOHM
J 0
(-8700 9250);
DISPLAY 1.212766 (-8700 9250);
PAINT GREEN (-8700 9250);
FORCEPROP 1 LAST CDS_LMAN_SYM_OUTLINE -50,50,100,-50
J 0
(-8600 9350);
DISPLAY 0.468085 (-8600 9350);
PAINT GREEN (-8600 9350);
DISPLAY INVISIBLE (-8600 9350);
FORCEPROP 2 LAST CDS_LIB passive
J 0
(-8600 9350);
DISPLAY INVISIBLE (-8600 9350);
FORCEPROP 1 LAST CLS_PN G155-11001-01
J 0
(-8736 9550);
DISPLAY 1.212766 (-8736 9550);
PAINT GREEN (-8736 9550);
DISPLAY INVISIBLE (-8736 9550);
FORCEPROP 1 LAST TOLERANCE 1%
J 0
(-8797 9605);
DISPLAY 1.212766 (-8797 9605);
PAINT GREEN (-8797 9605);
DISPLAY INVISIBLE (-8797 9605);
FORCEPROP 1 LAST PATH I121
J 0
(-8797 9455);
DISPLAY 1.212766 (-8797 9455);
PAINT GREEN (-8797 9455);
DISPLAY INVISIBLE (-8797 9455);
FORCEADD CAPACITOR..2
(-11450 10750);
FORCEPROP 1 LAST $LOCATION C90
J 0
(-11750 10600);
DISPLAY 1.212766 (-11750 10600);
PAINT GREEN (-11750 10600);
FORCEPROP 0 LAST CDS_LOCATION C90
J 0
(-11750 10600);
DISPLAY 1.212766 (-11750 10600);
PAINT GREEN (-11750 10600);
DISPLAY INVISIBLE (-11750 10600);
FORCEPROP 0 LAST $SEC 1
J 0
(-11750 10850);
DISPLAY 0.680851 (-11750 10850);
PAINT MONO (-11750 10850);
DISPLAY INVISIBLE (-11750 10850);
FORCEPROP 0 LAST CDS_SEC 1
J 0
(-11750 10850);
DISPLAY 1.021277 (-11750 10850);
DISPLAY INVISIBLE (-11750 10850);
FORCEPROP 0 LASTPIN (-11450 10850) $PN 1
R 1
J 0
(-11460 10860);
DISPLAY 0.680851 (-11460 10860);
PAINT MONO (-11460 10860);
FORCEPROP 0 LASTPIN (-11450 10600) $PN 2
R 1
J 2
(-11460 10590);
DISPLAY 0.680851 (-11460 10590);
PAINT MONO (-11460 10590);
FORCEPROP 1 LAST VALUE 4.7UF
J 0
(-11800 10700);
DISPLAY 1.212766 (-11800 10700);
PAINT GREEN (-11800 10700);
FORCEPROP 0 LAST PACKAGE 0402
J 0
(-11750 10800);
DISPLAY 1.021277 (-11750 10800);
FORCEPROP 1 LAST TOLERANCE 20%
J 0
(-11600 10850);
DISPLAY 1.212766 (-11600 10850);
PAINT GREEN (-11600 10850);
DISPLAY INVISIBLE (-11600 10850);
FORCEPROP 1 LAST CLS_PN G105-0F475-BM
J 0
(-11550 10800);
DISPLAY 1.212766 (-11550 10800);
PAINT GREEN (-11550 10800);
DISPLAY INVISIBLE (-11550 10800);
FORCEPROP 1 LAST CDS_LMAN_SYM_OUTLINE -50,0,50,-50
J 0
(-11450 10750);
DISPLAY 0.468085 (-11450 10750);
PAINT GREEN (-11450 10750);
DISPLAY INVISIBLE (-11450 10750);
FORCEPROP 2 LAST CDS_LIB passive
J 0
(-11450 10750);
DISPLAY INVISIBLE (-11450 10750);
FORCEPROP 1 LAST PATH I123
J 0
(-11550 10800);
DISPLAY 1.212766 (-11550 10800);
PAINT GREEN (-11550 10800);
DISPLAY INVISIBLE (-11550 10800);
FORCEADD GND_SG..1
(-10950 10350);
FORCEPROP 3 LASTPIN (-10900 10400) SIG_NAME SG\g
J 0
(-10890 10410);
DISPLAY 0.659574 (-10890 10410);
PAINT MONO (-10890 10410);
DISPLAY INVISIBLE (-10890 10410);
FORCEPROP 1 LAST HDL_POWER SG
J 1
(-10895 10255);
DISPLAY 0.808511 (-10895 10255);
PAINT GREEN (-10895 10255);
FORCEPROP 1 LAST BODY_TYPE PLUMBING
J 0
(-10935 10335);
DISPLAY 0.808511 (-10935 10335);
PAINT GREEN (-10935 10335);
DISPLAY INVISIBLE (-10935 10335);
FORCEPROP 1 LAST PATH I124
J 0
(-10915 10350);
DISPLAY 0.808511 (-10915 10350);
PAINT GREEN (-10915 10350);
DISPLAY INVISIBLE (-10915 10350);
FORCEPROP 1 LAST CDS_LMAN_SYM_OUTLINE 0,0,100,-50
J 0
(-10950 10350);
DISPLAY 0.468085 (-10950 10350);
PAINT GREEN (-10950 10350);
DISPLAY INVISIBLE (-10950 10350);
FORCEPROP 2 LAST CDS_LIB cls
J 0
(-10950 10350);
DISPLAY INVISIBLE (-10950 10350);
FORCEADD FERRITEBEAD..1
(-10000 11900);
FORCEPROP 1 LAST $LOCATION L4
J 2
(-10100 11900);
DISPLAY 1.212766 (-10100 11900);
PAINT GREEN (-10100 11900);
FORCEPROP 0 LAST CDS_LOCATION L4
J 0
(-10050 12100);
DISPLAY 1.021277 (-10050 12100);
DISPLAY INVISIBLE (-10050 12100);
FORCEPROP 0 LAST $SEC 1
J 0
(-10050 12100);
DISPLAY 0.680851 (-10050 12100);
PAINT MONO (-10050 12100);
DISPLAY INVISIBLE (-10050 12100);
FORCEPROP 0 LAST CDS_SEC 1
J 0
(-10050 12100);
DISPLAY 1.021277 (-10050 12100);
DISPLAY INVISIBLE (-10050 12100);
FORCEPROP 0 LASTPIN (-10100 11850) $PN 1
J 2
(-10110 11860);
DISPLAY 0.680851 (-10110 11860);
PAINT MONO (-10110 11860);
FORCEPROP 0 LASTPIN (-9700 11850) $PN 2
J 0
(-9690 11860);
DISPLAY 0.680851 (-9690 11860);
PAINT MONO (-9690 11860);
FORCEPROP 0 LAST DCR 1300MA 0.15OHM
J 0
(-10250 11750);
FORCEPROP 0 LAST PACKAGE 0603
J 0
(-10000 11950);
DISPLAY 1.021277 (-10000 11950);
FORCEPROP 1 LAST VALUE 600OHM
J 0
(-9600 11900);
DISPLAY 1.212766 (-9600 11900);
PAINT GREEN (-9600 11900);
FORCEPROP 1 LAST CDS_LMAN_SYM_OUTLINE 0,0,200,-100
J 0
(-10000 11900);
DISPLAY 0.468085 (-10000 11900);
PAINT GREEN (-10000 11900);
DISPLAY INVISIBLE (-10000 11900);
FORCEPROP 2 LAST CDS_LIB passive
J 0
(-10000 11900);
DISPLAY INVISIBLE (-10000 11900);
FORCEPROP 1 LAST PATH I127
J 2
(-10050 11950);
DISPLAY 1.212766 (-10050 11950);
PAINT GREEN (-10050 11950);
DISPLAY INVISIBLE (-10050 11950);
FORCEPROP 1 LAST TOLERANCE 25%
J 0
(-10100 11950);
DISPLAY 1.212766 (-10100 11950);
PAINT GREEN (-10100 11950);
DISPLAY INVISIBLE (-10100 11950);
FORCEPROP 1 LAST CLS_PN G191-10097-01
J 2
(-10050 11950);
DISPLAY 1.212766 (-10050 11950);
PAINT GREEN (-10050 11950);
DISPLAY INVISIBLE (-10050 11950);
FORCEADD CAPACITOR..2
(-11450 11650);
FORCEPROP 1 LAST $LOCATION C91
J 0
(-11350 11450);
DISPLAY 1.212766 (-11350 11450);
PAINT GREEN (-11350 11450);
FORCEPROP 0 LAST CDS_LOCATION C91
J 0
(-11750 11500);
DISPLAY 1.212766 (-11750 11500);
PAINT GREEN (-11750 11500);
DISPLAY INVISIBLE (-11750 11500);
FORCEPROP 0 LAST $SEC 1
J 0
(-11750 11800);
DISPLAY 0.680851 (-11750 11800);
PAINT MONO (-11750 11800);
DISPLAY INVISIBLE (-11750 11800);
FORCEPROP 0 LAST CDS_SEC 1
J 0
(-11750 11800);
DISPLAY 1.021277 (-11750 11800);
DISPLAY INVISIBLE (-11750 11800);
FORCEPROP 0 LASTPIN (-11450 11750) $PN 1
R 1
J 0
(-11460 11760);
DISPLAY 0.680851 (-11460 11760);
PAINT MONO (-11460 11760);
FORCEPROP 0 LASTPIN (-11450 11500) $PN 2
R 1
J 2
(-11460 11490);
DISPLAY 0.680851 (-11460 11490);
PAINT MONO (-11460 11490);
FORCEPROP 0 LAST VOLTAGE 6.3V
J 0
(-11350 11750);
DISPLAY 1.021277 (-11350 11750);
FORCEPROP 0 LAST PACKAGE 0402
J 0
(-11350 11650);
DISPLAY 1.021277 (-11350 11650);
FORCEPROP 1 LAST VALUE 4.7UF
J 0
(-11400 11550);
DISPLAY 1.212766 (-11400 11550);
PAINT GREEN (-11400 11550);
FORCEPROP 1 LAST PATH I128
J 0
(-11550 11700);
DISPLAY 1.212766 (-11550 11700);
PAINT GREEN (-11550 11700);
DISPLAY INVISIBLE (-11550 11700);
FORCEPROP 2 LAST CDS_LIB passive
J 0
(-11450 11650);
DISPLAY INVISIBLE (-11450 11650);
FORCEPROP 1 LAST CDS_LMAN_SYM_OUTLINE -50,0,50,-50
J 0
(-11450 11650);
DISPLAY 0.468085 (-11450 11650);
PAINT GREEN (-11450 11650);
DISPLAY INVISIBLE (-11450 11650);
FORCEPROP 1 LAST CLS_PN G105-0F475-BM
J 0
(-11550 11700);
DISPLAY 1.212766 (-11550 11700);
PAINT GREEN (-11550 11700);
DISPLAY INVISIBLE (-11550 11700);
FORCEPROP 1 LAST TOLERANCE 20%
J 0
(-11600 11750);
DISPLAY 1.212766 (-11600 11750);
PAINT GREEN (-11600 11750);
DISPLAY INVISIBLE (-11600 11750);
FORCEADD OFFPAGE_OUT..1
(-2850 11150);
FORCEPROP 2 LAST $XR0 24J1< 
J 0
(-2795 11150);
DISPLAY 0.638298 (-2795 11150);
PAINT MONO (-2795 11150);
FORCEPROP 2 LAST CDS_LIB cls
J 0
(-2850 11150);
DISPLAY INVISIBLE (-2850 11150);
FORCEPROP 1 LAST CDS_LMAN_SYM_OUTLINE -50,50,50,-50
J 0
(-2850 11150);
DISPLAY 0.468085 (-2850 11150);
PAINT GREEN (-2850 11150);
DISPLAY INVISIBLE (-2850 11150);
FORCEPROP 2 LAST PATH I135
J 0
(-2800 11250);
DISPLAY 1.021277 (-2800 11250);
DISPLAY INVISIBLE (-2800 11250);
FORCEPROP 1 LAST OFFPAGE TRUE
J 0
(-2840 11205);
DISPLAY 0.808511 (-2840 11205);
PAINT GREEN (-2840 11205);
DISPLAY INVISIBLE (-2840 11205);
FORCEPROP 1 LAST BODY_TYPE COMMENT
J 0
(-2840 11285);
DISPLAY 0.808511 (-2840 11285);
PAINT GREEN (-2840 11285);
DISPLAY INVISIBLE (-2840 11285);
FORCEADD OFFPAGE_OUT..1
(-2850 11350);
FORCEPROP 2 LAST $XR0 24H1< 
J 0
(-2795 11350);
DISPLAY 0.638298 (-2795 11350);
PAINT MONO (-2795 11350);
FORCEPROP 2 LAST PATH I136
J 0
(-2800 11450);
DISPLAY 1.021277 (-2800 11450);
DISPLAY INVISIBLE (-2800 11450);
FORCEPROP 1 LAST OFFPAGE TRUE
J 0
(-2840 11405);
DISPLAY 0.808511 (-2840 11405);
PAINT GREEN (-2840 11405);
DISPLAY INVISIBLE (-2840 11405);
FORCEPROP 2 LAST CDS_LIB cls
J 0
(-2850 11350);
DISPLAY INVISIBLE (-2850 11350);
FORCEPROP 1 LAST CDS_LMAN_SYM_OUTLINE -50,50,50,-50
J 0
(-2850 11350);
DISPLAY 0.468085 (-2850 11350);
PAINT GREEN (-2850 11350);
DISPLAY INVISIBLE (-2850 11350);
FORCEPROP 1 LAST BODY_TYPE COMMENT
J 0
(-2840 11485);
DISPLAY 0.808511 (-2840 11485);
PAINT GREEN (-2840 11485);
DISPLAY INVISIBLE (-2840 11485);
FORCEADD OFFPAGE_OUT..1
(-2850 11450);
FORCEPROP 2 LAST $XR0 24H1< 
J 0
(-2795 11450);
DISPLAY 0.638298 (-2795 11450);
PAINT MONO (-2795 11450);
FORCEPROP 2 LAST PATH I137
J 0
(-2800 11550);
DISPLAY 1.021277 (-2800 11550);
DISPLAY INVISIBLE (-2800 11550);
FORCEPROP 1 LAST OFFPAGE TRUE
J 0
(-2840 11505);
DISPLAY 0.808511 (-2840 11505);
PAINT GREEN (-2840 11505);
DISPLAY INVISIBLE (-2840 11505);
FORCEPROP 2 LAST CDS_LIB cls
J 0
(-2850 11450);
DISPLAY INVISIBLE (-2850 11450);
FORCEPROP 1 LAST CDS_LMAN_SYM_OUTLINE -50,50,50,-50
J 0
(-2850 11450);
DISPLAY 0.468085 (-2850 11450);
PAINT GREEN (-2850 11450);
DISPLAY INVISIBLE (-2850 11450);
FORCEPROP 1 LAST BODY_TYPE COMMENT
J 0
(-2840 11585);
DISPLAY 0.808511 (-2840 11585);
PAINT GREEN (-2840 11585);
DISPLAY INVISIBLE (-2840 11585);
FORCEADD OFFPAGE_IN..2
(-2850 11250);
FORCEPROP 2 LAST $XR0 24J1> 
J 0
(-2795 11250);
DISPLAY 0.638298 (-2795 11250);
PAINT MONO (-2795 11250);
FORCEPROP 2 LAST PATH I138
J 0
(-2800 11350);
DISPLAY 1.021277 (-2800 11350);
DISPLAY INVISIBLE (-2800 11350);
FORCEPROP 1 LAST OFFPAGE TRUE
J 0
(-2840 11305);
DISPLAY 0.808511 (-2840 11305);
PAINT GREEN (-2840 11305);
DISPLAY INVISIBLE (-2840 11305);
FORCEPROP 2 LAST CDS_LIB cls
J 0
(-2850 11250);
DISPLAY INVISIBLE (-2850 11250);
FORCEPROP 1 LAST CDS_LMAN_SYM_OUTLINE -50,50,50,-50
J 0
(-2850 11250);
DISPLAY 0.468085 (-2850 11250);
PAINT GREEN (-2850 11250);
DISPLAY INVISIBLE (-2850 11250);
FORCEPROP 1 LAST BODY_TYPE COMMENT
J 0
(-2840 11385);
DISPLAY 0.808511 (-2840 11385);
PAINT GREEN (-2840 11385);
DISPLAY INVISIBLE (-2840 11385);
FORCEADD RESISTOR..1
(-5300 11150);
FORCEPROP 1 LAST $LOCATION R470
J 2
(-5500 11150);
DISPLAY 1.212766 (-5500 11150);
PAINT GREEN (-5500 11150);
FORCEPROP 0 LAST CDS_LOCATION R470
J 0
(-5050 11250);
DISPLAY 1.021277 (-5050 11250);
DISPLAY INVISIBLE (-5050 11250);
FORCEPROP 0 LAST $SEC 1
J 0
(-5050 11250);
DISPLAY 0.680851 (-5050 11250);
PAINT MONO (-5050 11250);
DISPLAY INVISIBLE (-5050 11250);
FORCEPROP 0 LAST CDS_SEC 1
J 0
(-5050 11250);
DISPLAY 1.021277 (-5050 11250);
DISPLAY INVISIBLE (-5050 11250);
FORCEPROP 0 LASTPIN (-5400 11150) $PN 1
J 2
(-5410 11160);
DISPLAY 0.680851 (-5410 11160);
PAINT MONO (-5410 11160);
FORCEPROP 0 LASTPIN (-5150 11150) $PN 2
J 0
(-5140 11160);
DISPLAY 0.680851 (-5140 11160);
PAINT MONO (-5140 11160);
FORCEPROP 1 LAST VALUE 33OHM
J 0
(-5061 11155);
DISPLAY 1.212766 (-5061 11155);
PAINT GREEN (-5061 11155);
FORCEPROP 0 LAST PACKAGE 0402
J 0
(-5350 11150);
DISPLAY 0.638298 (-5350 11150);
FORCEPROP 1 LAST PATH I139
J 0
(-5497 11255);
DISPLAY 1.212766 (-5497 11255);
PAINT GREEN (-5497 11255);
DISPLAY INVISIBLE (-5497 11255);
FORCEPROP 1 LAST TOLERANCE 1%
J 0
(-5497 11405);
DISPLAY 1.212766 (-5497 11405);
PAINT GREEN (-5497 11405);
DISPLAY INVISIBLE (-5497 11405);
FORCEPROP 1 LAST CLS_PN G155-133R0-01
J 0
(-5436 11350);
DISPLAY 1.212766 (-5436 11350);
PAINT GREEN (-5436 11350);
DISPLAY INVISIBLE (-5436 11350);
FORCEPROP 1 LAST CDS_LMAN_SYM_OUTLINE -50,50,100,-50
J 0
(-5300 11150);
DISPLAY 0.468085 (-5300 11150);
PAINT GREEN (-5300 11150);
DISPLAY INVISIBLE (-5300 11150);
FORCEPROP 2 LAST CDS_LIB passive
J 0
(-5300 11150);
DISPLAY INVISIBLE (-5300 11150);
FORCEADD RESISTOR..1
(-5300 11350);
FORCEPROP 1 LAST $LOCATION R468
J 2
(-5500 11350);
DISPLAY 1.212766 (-5500 11350);
PAINT GREEN (-5500 11350);
FORCEPROP 0 LAST CDS_LOCATION R468
J 0
(-5050 11450);
DISPLAY 1.021277 (-5050 11450);
DISPLAY INVISIBLE (-5050 11450);
FORCEPROP 0 LAST $SEC 1
J 0
(-5050 11450);
DISPLAY 0.680851 (-5050 11450);
PAINT MONO (-5050 11450);
DISPLAY INVISIBLE (-5050 11450);
FORCEPROP 0 LAST CDS_SEC 1
J 0
(-5050 11450);
DISPLAY 1.021277 (-5050 11450);
DISPLAY INVISIBLE (-5050 11450);
FORCEPROP 0 LASTPIN (-5400 11350) $PN 1
J 2
(-5410 11360);
DISPLAY 0.680851 (-5410 11360);
PAINT MONO (-5410 11360);
FORCEPROP 0 LASTPIN (-5150 11350) $PN 2
J 0
(-5140 11360);
DISPLAY 0.680851 (-5140 11360);
PAINT MONO (-5140 11360);
FORCEPROP 1 LAST VALUE 33OHM
J 0
(-5061 11355);
DISPLAY 1.212766 (-5061 11355);
PAINT GREEN (-5061 11355);
FORCEPROP 0 LAST PACKAGE 0402
J 0
(-5350 11350);
DISPLAY 0.638298 (-5350 11350);
FORCEPROP 1 LAST CDS_LMAN_SYM_OUTLINE -50,50,100,-50
J 0
(-5300 11350);
DISPLAY 0.468085 (-5300 11350);
PAINT GREEN (-5300 11350);
DISPLAY INVISIBLE (-5300 11350);
FORCEPROP 2 LAST CDS_LIB passive
J 0
(-5300 11350);
DISPLAY INVISIBLE (-5300 11350);
FORCEPROP 1 LAST PATH I140
J 0
(-5497 11455);
DISPLAY 1.212766 (-5497 11455);
PAINT GREEN (-5497 11455);
DISPLAY INVISIBLE (-5497 11455);
FORCEPROP 1 LAST TOLERANCE 1%
J 0
(-5497 11605);
DISPLAY 1.212766 (-5497 11605);
PAINT GREEN (-5497 11605);
DISPLAY INVISIBLE (-5497 11605);
FORCEPROP 1 LAST CLS_PN G155-133R0-01
J 0
(-5436 11550);
DISPLAY 1.212766 (-5436 11550);
PAINT GREEN (-5436 11550);
DISPLAY INVISIBLE (-5436 11550);
FORCEADD RESISTOR..1
(-5300 11450);
FORCEPROP 1 LAST $LOCATION R467
J 2
(-5500 11450);
DISPLAY 1.212766 (-5500 11450);
PAINT GREEN (-5500 11450);
FORCEPROP 0 LAST CDS_LOCATION R467
J 0
(-5050 11550);
DISPLAY 1.021277 (-5050 11550);
DISPLAY INVISIBLE (-5050 11550);
FORCEPROP 0 LAST $SEC 1
J 0
(-5050 11550);
DISPLAY 0.680851 (-5050 11550);
PAINT MONO (-5050 11550);
DISPLAY INVISIBLE (-5050 11550);
FORCEPROP 0 LAST CDS_SEC 1
J 0
(-5050 11550);
DISPLAY 1.021277 (-5050 11550);
DISPLAY INVISIBLE (-5050 11550);
FORCEPROP 0 LASTPIN (-5400 11450) $PN 1
J 2
(-5410 11460);
DISPLAY 0.680851 (-5410 11460);
PAINT MONO (-5410 11460);
FORCEPROP 0 LASTPIN (-5150 11450) $PN 2
J 0
(-5140 11460);
DISPLAY 0.680851 (-5140 11460);
PAINT MONO (-5140 11460);
FORCEPROP 0 LAST PACKAGE 0402
J 0
(-5350 11450);
DISPLAY 0.638298 (-5350 11450);
FORCEPROP 1 LAST VALUE 33OHM
J 0
(-5061 11455);
DISPLAY 1.212766 (-5061 11455);
PAINT GREEN (-5061 11455);
FORCEPROP 1 LAST CDS_LMAN_SYM_OUTLINE -50,50,100,-50
J 0
(-5300 11450);
DISPLAY 0.468085 (-5300 11450);
PAINT GREEN (-5300 11450);
DISPLAY INVISIBLE (-5300 11450);
FORCEPROP 2 LAST CDS_LIB passive
J 0
(-5300 11450);
DISPLAY INVISIBLE (-5300 11450);
FORCEPROP 1 LAST PATH I141
J 0
(-5497 11555);
DISPLAY 1.212766 (-5497 11555);
PAINT GREEN (-5497 11555);
DISPLAY INVISIBLE (-5497 11555);
FORCEPROP 1 LAST TOLERANCE 1%
J 0
(-5497 11705);
DISPLAY 1.212766 (-5497 11705);
PAINT GREEN (-5497 11705);
DISPLAY INVISIBLE (-5497 11705);
FORCEPROP 1 LAST CLS_PN G155-133R0-01
J 0
(-5436 11650);
DISPLAY 1.212766 (-5436 11650);
PAINT GREEN (-5436 11650);
DISPLAY INVISIBLE (-5436 11650);
FORCEADD RESISTOR..1
(-5300 11250);
FORCEPROP 1 LAST $LOCATION R469
J 2
(-5500 11250);
DISPLAY 1.212766 (-5500 11250);
PAINT GREEN (-5500 11250);
FORCEPROP 0 LAST CDS_LOCATION R469
J 0
(-5050 11350);
DISPLAY 1.021277 (-5050 11350);
DISPLAY INVISIBLE (-5050 11350);
FORCEPROP 0 LAST $SEC 1
J 0
(-5050 11350);
DISPLAY 0.680851 (-5050 11350);
PAINT MONO (-5050 11350);
DISPLAY INVISIBLE (-5050 11350);
FORCEPROP 0 LAST CDS_SEC 1
J 0
(-5050 11350);
DISPLAY 1.021277 (-5050 11350);
DISPLAY INVISIBLE (-5050 11350);
FORCEPROP 0 LASTPIN (-5400 11250) $PN 1
J 2
(-5410 11260);
DISPLAY 0.680851 (-5410 11260);
PAINT MONO (-5410 11260);
FORCEPROP 0 LASTPIN (-5150 11250) $PN 2
J 0
(-5140 11260);
DISPLAY 0.680851 (-5140 11260);
PAINT MONO (-5140 11260);
FORCEPROP 1 LAST VALUE 33OHM
J 0
(-5061 11255);
DISPLAY 1.212766 (-5061 11255);
PAINT GREEN (-5061 11255);
FORCEPROP 0 LAST PACKAGE 0402
J 0
(-5350 11250);
DISPLAY 0.638298 (-5350 11250);
FORCEPROP 1 LAST PATH I142
J 0
(-5497 11355);
DISPLAY 1.212766 (-5497 11355);
PAINT GREEN (-5497 11355);
DISPLAY INVISIBLE (-5497 11355);
FORCEPROP 1 LAST TOLERANCE 1%
J 0
(-5497 11505);
DISPLAY 1.212766 (-5497 11505);
PAINT GREEN (-5497 11505);
DISPLAY INVISIBLE (-5497 11505);
FORCEPROP 1 LAST CLS_PN G155-133R0-01
J 0
(-5436 11450);
DISPLAY 1.212766 (-5436 11450);
PAINT GREEN (-5436 11450);
DISPLAY INVISIBLE (-5436 11450);
FORCEPROP 1 LAST CDS_LMAN_SYM_OUTLINE -50,50,100,-50
J 0
(-5300 11250);
DISPLAY 0.468085 (-5300 11250);
PAINT GREEN (-5300 11250);
DISPLAY INVISIBLE (-5300 11250);
FORCEPROP 2 LAST CDS_LIB passive
J 0
(-5300 11250);
DISPLAY INVISIBLE (-5300 11250);
FORCEADD OFFPAGE_OUT..1
(-2850 9650);
FORCEPROP 2 LAST $XR0 11H12< 
J 0
(-2795 9650);
DISPLAY 0.638298 (-2795 9650);
PAINT MONO (-2795 9650);
FORCEPROP 2 LAST PATH I146
J 0
(-2750 9700);
DISPLAY 1.021277 (-2750 9700);
DISPLAY INVISIBLE (-2750 9700);
FORCEPROP 1 LAST OFFPAGE TRUE
J 0
(-2840 9705);
DISPLAY 0.808511 (-2840 9705);
PAINT GREEN (-2840 9705);
DISPLAY INVISIBLE (-2840 9705);
FORCEPROP 1 LAST BODY_TYPE COMMENT
J 0
(-2840 9785);
DISPLAY 0.808511 (-2840 9785);
PAINT GREEN (-2840 9785);
DISPLAY INVISIBLE (-2840 9785);
FORCEPROP 1 LAST CDS_LMAN_SYM_OUTLINE -50,50,50,-50
J 0
(-2850 9650);
DISPLAY 0.468085 (-2850 9650);
PAINT GREEN (-2850 9650);
DISPLAY INVISIBLE (-2850 9650);
FORCEPROP 2 LAST CDS_LIB cls
J 0
(-2850 9650);
DISPLAY INVISIBLE (-2850 9650);
FORCEADD OFFPAGE_IN..2
(-2850 9550);
FORCEPROP 2 LAST $XR0 11H12> 
J 0
(-2795 9550);
DISPLAY 0.638298 (-2795 9550);
PAINT MONO (-2795 9550);
FORCEPROP 2 LAST PATH I147
J 0
(-2750 9600);
DISPLAY 1.021277 (-2750 9600);
DISPLAY INVISIBLE (-2750 9600);
FORCEPROP 1 LAST OFFPAGE TRUE
J 0
(-2840 9605);
DISPLAY 0.808511 (-2840 9605);
PAINT GREEN (-2840 9605);
DISPLAY INVISIBLE (-2840 9605);
FORCEPROP 1 LAST BODY_TYPE COMMENT
J 0
(-2840 9685);
DISPLAY 0.808511 (-2840 9685);
PAINT GREEN (-2840 9685);
DISPLAY INVISIBLE (-2840 9685);
FORCEPROP 1 LAST CDS_LMAN_SYM_OUTLINE -50,50,50,-50
J 0
(-2850 9550);
DISPLAY 0.468085 (-2850 9550);
PAINT GREEN (-2850 9550);
DISPLAY INVISIBLE (-2850 9550);
FORCEPROP 2 LAST CDS_LIB cls
J 0
(-2850 9550);
DISPLAY INVISIBLE (-2850 9550);
FORCEADD RESISTOR..2
R 1
(-4200 9200);
FORCEPROP 1 LAST $LOCATION R480
J 0
(-4550 9200);
DISPLAY 1.212766 (-4550 9200);
PAINT GREEN (-4550 9200);
FORCEPROP 0 LAST CDS_LOCATION R480
R 1
J 0
(-4000 9300);
DISPLAY 1.021277 (-4000 9300);
DISPLAY INVISIBLE (-4000 9300);
FORCEPROP 0 LAST $SEC 1
R 1
J 0
(-4000 9300);
DISPLAY 0.680851 (-4000 9300);
PAINT MONO (-4000 9300);
DISPLAY INVISIBLE (-4000 9300);
FORCEPROP 0 LAST CDS_SEC 1
R 1
J 0
(-4000 9300);
DISPLAY 1.021277 (-4000 9300);
DISPLAY INVISIBLE (-4000 9300);
FORCEPROP 0 LASTPIN (-4300 9200) $PN 1
J 2
(-4310 9210);
DISPLAY 0.680851 (-4310 9210);
PAINT MONO (-4310 9210);
FORCEPROP 0 LASTPIN (-4050 9200) $PN 2
J 0
(-4040 9210);
DISPLAY 0.680851 (-4040 9210);
PAINT MONO (-4040 9210);
FORCEPROP 0 LAST PACKAGE 0402
J 0
(-4250 9250);
DISPLAY 0.808511 (-4250 9250);
FORCEPROP 1 LAST VALUE 100KOHM
J 0
(-4000 9200);
DISPLAY 1.212766 (-4000 9200);
PAINT GREEN (-4000 9200);
FORCEPROP 1 LAST TOLERANCE 1%
R 1
J 0
(-4455 9003);
DISPLAY 1.212766 (-4455 9003);
PAINT GREEN (-4455 9003);
DISPLAY INVISIBLE (-4455 9003);
FORCEPROP 2 LAST CDS_LIB passive
J 0
(-4200 9200);
DISPLAY INVISIBLE (-4200 9200);
FORCEPROP 1 LAST CDS_LMAN_SYM_OUTLINE -50,50,50,-100
R 1
J 0
(-4200 9200);
DISPLAY 0.468085 (-4200 9200);
PAINT GREEN (-4200 9200);
DISPLAY INVISIBLE (-4200 9200);
FORCEPROP 1 LAST CLS_PN G155-11003-01
R 1
J 0
(-4400 9064);
DISPLAY 1.212766 (-4400 9064);
PAINT GREEN (-4400 9064);
DISPLAY INVISIBLE (-4400 9064);
FORCEPROP 1 LAST PATH I149
R 1
J 0
(-4305 9003);
DISPLAY 1.212766 (-4305 9003);
PAINT GREEN (-4305 9003);
DISPLAY INVISIBLE (-4305 9003);
FORCEADD RESISTOR..2
R 1
(-4200 9100);
FORCEPROP 1 LAST $LOCATION R481
J 0
(-4550 9100);
DISPLAY 1.212766 (-4550 9100);
PAINT GREEN (-4550 9100);
FORCEPROP 0 LAST CDS_LOCATION R481
R 1
J 0
(-4000 9200);
DISPLAY 1.021277 (-4000 9200);
DISPLAY INVISIBLE (-4000 9200);
FORCEPROP 0 LAST $SEC 1
R 1
J 0
(-4000 9200);
DISPLAY 0.680851 (-4000 9200);
PAINT MONO (-4000 9200);
DISPLAY INVISIBLE (-4000 9200);
FORCEPROP 0 LAST CDS_SEC 1
R 1
J 0
(-4000 9200);
DISPLAY 1.021277 (-4000 9200);
DISPLAY INVISIBLE (-4000 9200);
FORCEPROP 0 LASTPIN (-4300 9100) $PN 1
J 2
(-4310 9110);
DISPLAY 0.680851 (-4310 9110);
PAINT MONO (-4310 9110);
FORCEPROP 0 LASTPIN (-4050 9100) $PN 2
J 0
(-4040 9110);
DISPLAY 0.680851 (-4040 9110);
PAINT MONO (-4040 9110);
FORCEPROP 1 LAST VALUE 100KOHM
J 0
(-4000 9100);
DISPLAY 1.212766 (-4000 9100);
PAINT GREEN (-4000 9100);
FORCEPROP 0 LAST PACKAGE 0402
J 0
(-4250 9050);
DISPLAY 0.808511 (-4250 9050);
FORCEPROP 1 LAST TOLERANCE 1%
R 1
J 0
(-4455 8903);
DISPLAY 1.212766 (-4455 8903);
PAINT GREEN (-4455 8903);
DISPLAY INVISIBLE (-4455 8903);
FORCEPROP 2 LAST CDS_LIB passive
J 0
(-4200 9100);
DISPLAY INVISIBLE (-4200 9100);
FORCEPROP 1 LAST CDS_LMAN_SYM_OUTLINE -50,50,50,-100
R 1
J 0
(-4200 9100);
DISPLAY 0.468085 (-4200 9100);
PAINT GREEN (-4200 9100);
DISPLAY INVISIBLE (-4200 9100);
FORCEPROP 1 LAST CLS_PN G155-11003-01
R 1
J 0
(-4400 8964);
DISPLAY 1.212766 (-4400 8964);
PAINT GREEN (-4400 8964);
DISPLAY INVISIBLE (-4400 8964);
FORCEPROP 1 LAST PATH I150
R 1
J 0
(-4305 8903);
DISPLAY 1.212766 (-4305 8903);
PAINT GREEN (-4305 8903);
DISPLAY INVISIBLE (-4305 8903);
FORCEADD RESISTOR..1
(-5300 9650);
FORCEPROP 1 LAST $LOCATION R353
J 2
(-5500 9650);
DISPLAY 1.212766 (-5500 9650);
PAINT GREEN (-5500 9650);
FORCEPROP 0 LAST CDS_LOCATION R353
J 0
(-5500 9850);
DISPLAY 1.021277 (-5500 9850);
DISPLAY INVISIBLE (-5500 9850);
FORCEPROP 0 LAST $SEC 1
J 0
(-5500 9850);
DISPLAY 0.680851 (-5500 9850);
PAINT MONO (-5500 9850);
DISPLAY INVISIBLE (-5500 9850);
FORCEPROP 0 LAST CDS_SEC 1
J 0
(-5500 9850);
DISPLAY 1.021277 (-5500 9850);
DISPLAY INVISIBLE (-5500 9850);
FORCEPROP 0 LASTPIN (-5400 9650) $PN 1
J 2
(-5410 9660);
DISPLAY 0.680851 (-5410 9660);
PAINT MONO (-5410 9660);
FORCEPROP 0 LASTPIN (-5150 9650) $PN 2
J 0
(-5140 9660);
DISPLAY 0.680851 (-5140 9660);
PAINT MONO (-5140 9660);
FORCEPROP 0 LAST PACKAGE 0402
J 0
(-5350 9700);
DISPLAY 0.808511 (-5350 9700);
FORCEPROP 1 LAST VALUE 100OHM
J 0
(-5050 9650);
DISPLAY 1.212766 (-5050 9650);
PAINT GREEN (-5050 9650);
FORCEPROP 1 LAST PATH I153
J 0
(-5497 9755);
DISPLAY 1.212766 (-5497 9755);
PAINT GREEN (-5497 9755);
DISPLAY INVISIBLE (-5497 9755);
FORCEPROP 1 LAST TOLERANCE 1%
J 0
(-5497 9905);
DISPLAY 1.212766 (-5497 9905);
PAINT GREEN (-5497 9905);
DISPLAY INVISIBLE (-5497 9905);
FORCEPROP 2 LAST CDS_LIB passive
J 0
(-5300 9650);
DISPLAY INVISIBLE (-5300 9650);
FORCEPROP 1 LAST CDS_LMAN_SYM_OUTLINE -50,50,100,-50
J 0
(-5300 9650);
DISPLAY 0.468085 (-5300 9650);
PAINT GREEN (-5300 9650);
DISPLAY INVISIBLE (-5300 9650);
FORCEPROP 1 LAST CLS_PN G155-11000-01
J 0
(-5436 9850);
DISPLAY 1.212766 (-5436 9850);
PAINT GREEN (-5436 9850);
DISPLAY INVISIBLE (-5436 9850);
FORCEADD RESISTOR..1
(-5300 9550);
FORCEPROP 1 LAST $LOCATION R352
J 2
(-5500 9550);
DISPLAY 1.212766 (-5500 9550);
PAINT GREEN (-5500 9550);
FORCEPROP 0 LAST CDS_LOCATION R352
J 0
(-5050 9650);
DISPLAY 1.021277 (-5050 9650);
DISPLAY INVISIBLE (-5050 9650);
FORCEPROP 0 LAST $SEC 1
J 0
(-5050 9650);
DISPLAY 0.680851 (-5050 9650);
PAINT MONO (-5050 9650);
DISPLAY INVISIBLE (-5050 9650);
FORCEPROP 0 LAST CDS_SEC 1
J 0
(-5050 9650);
DISPLAY 1.021277 (-5050 9650);
DISPLAY INVISIBLE (-5050 9650);
FORCEPROP 0 LASTPIN (-5400 9550) $PN 1
J 2
(-5410 9560);
DISPLAY 0.680851 (-5410 9560);
PAINT MONO (-5410 9560);
FORCEPROP 0 LASTPIN (-5150 9550) $PN 2
J 0
(-5140 9560);
DISPLAY 0.680851 (-5140 9560);
PAINT MONO (-5140 9560);
FORCEPROP 1 LAST VALUE 100OHM
J 0
(-5050 9550);
DISPLAY 1.212766 (-5050 9550);
PAINT GREEN (-5050 9550);
FORCEPROP 0 LAST PACKAGE 0402
J 0
(-5350 9450);
DISPLAY 0.808511 (-5350 9450);
FORCEPROP 1 LAST PATH I154
J 0
(-5497 9655);
DISPLAY 1.212766 (-5497 9655);
PAINT GREEN (-5497 9655);
DISPLAY INVISIBLE (-5497 9655);
FORCEPROP 1 LAST TOLERANCE 1%
J 0
(-5497 9805);
DISPLAY 1.212766 (-5497 9805);
PAINT GREEN (-5497 9805);
DISPLAY INVISIBLE (-5497 9805);
FORCEPROP 2 LAST CDS_LIB passive
J 0
(-5300 9550);
DISPLAY INVISIBLE (-5300 9550);
FORCEPROP 1 LAST CDS_LMAN_SYM_OUTLINE -50,50,100,-50
J 0
(-5300 9550);
DISPLAY 0.468085 (-5300 9550);
PAINT GREEN (-5300 9550);
DISPLAY INVISIBLE (-5300 9550);
FORCEPROP 1 LAST CLS_PN G155-11000-01
J 0
(-5436 9750);
DISPLAY 1.212766 (-5436 9750);
PAINT GREEN (-5436 9750);
DISPLAY INVISIBLE (-5436 9750);
FORCEADD RESISTOR..1
(-5300 10450);
FORCEPROP 1 LAST $LOCATION R472
J 2
(-5500 10450);
DISPLAY 1.212766 (-5500 10450);
PAINT GREEN (-5500 10450);
FORCEPROP 0 LAST CDS_LOCATION R472
J 0
(-5050 10550);
DISPLAY 1.021277 (-5050 10550);
DISPLAY INVISIBLE (-5050 10550);
FORCEPROP 0 LAST $SEC 1
J 0
(-5050 10550);
DISPLAY 0.680851 (-5050 10550);
PAINT MONO (-5050 10550);
DISPLAY INVISIBLE (-5050 10550);
FORCEPROP 0 LAST CDS_SEC 1
J 0
(-5050 10550);
DISPLAY 1.021277 (-5050 10550);
DISPLAY INVISIBLE (-5050 10550);
FORCEPROP 0 LASTPIN (-5400 10450) $PN 1
J 2
(-5410 10460);
DISPLAY 0.680851 (-5410 10460);
PAINT MONO (-5410 10460);
FORCEPROP 0 LASTPIN (-5150 10450) $PN 2
J 0
(-5140 10460);
DISPLAY 0.680851 (-5140 10460);
PAINT MONO (-5140 10460);
FORCEPROP 0 LAST PACKAGE 0402
J 0
(-5350 10450);
DISPLAY 0.638298 (-5350 10450);
FORCEPROP 1 LAST VALUE 0OHM
J 0
(-5061 10455);
DISPLAY 1.212766 (-5061 10455);
PAINT GREEN (-5061 10455);
FORCEPROP 1 LAST CDS_LMAN_SYM_OUTLINE -50,50,100,-50
J 0
(-5300 10450);
DISPLAY 0.468085 (-5300 10450);
PAINT GREEN (-5300 10450);
DISPLAY INVISIBLE (-5300 10450);
FORCEPROP 2 LAST CDS_LIB passive
J 0
(-5300 10450);
DISPLAY INVISIBLE (-5300 10450);
FORCEPROP 1 LAST PATH I166
J 0
(-5497 10555);
DISPLAY 1.212766 (-5497 10555);
PAINT GREEN (-5497 10555);
DISPLAY INVISIBLE (-5497 10555);
FORCEPROP 1 LAST TOLERANCE -
J 0
(-5497 10705);
DISPLAY 1.212766 (-5497 10705);
PAINT GREEN (-5497 10705);
DISPLAY INVISIBLE (-5497 10705);
FORCEPROP 1 LAST CLS_PN G155-100R0-J0
J 0
(-5436 10650);
DISPLAY 1.212766 (-5436 10650);
PAINT GREEN (-5436 10650);
DISPLAY INVISIBLE (-5436 10650);
FORCEADD RESISTOR..1
(-5300 10550);
FORCEPROP 1 LAST $LOCATION R471
J 2
(-5500 10550);
DISPLAY 1.212766 (-5500 10550);
PAINT GREEN (-5500 10550);
FORCEPROP 0 LAST CDS_LOCATION R471
J 0
(-5050 10650);
DISPLAY 1.021277 (-5050 10650);
DISPLAY INVISIBLE (-5050 10650);
FORCEPROP 0 LAST $SEC 1
J 0
(-5050 10650);
DISPLAY 0.680851 (-5050 10650);
PAINT MONO (-5050 10650);
DISPLAY INVISIBLE (-5050 10650);
FORCEPROP 0 LAST CDS_SEC 1
J 0
(-5050 10650);
DISPLAY 1.021277 (-5050 10650);
DISPLAY INVISIBLE (-5050 10650);
FORCEPROP 0 LASTPIN (-5400 10550) $PN 1
J 2
(-5410 10560);
DISPLAY 0.680851 (-5410 10560);
PAINT MONO (-5410 10560);
FORCEPROP 0 LASTPIN (-5150 10550) $PN 2
J 0
(-5140 10560);
DISPLAY 0.680851 (-5140 10560);
PAINT MONO (-5140 10560);
FORCEPROP 1 LAST VALUE 0OHM
J 0
(-5061 10555);
DISPLAY 1.212766 (-5061 10555);
PAINT GREEN (-5061 10555);
FORCEPROP 0 LAST PACKAGE 0402
J 0
(-5350 10550);
DISPLAY 0.638298 (-5350 10550);
FORCEPROP 2 LAST CDS_LIB passive
J 0
(-5300 10550);
DISPLAY INVISIBLE (-5300 10550);
FORCEPROP 1 LAST CDS_LMAN_SYM_OUTLINE -50,50,100,-50
J 0
(-5300 10550);
DISPLAY 0.468085 (-5300 10550);
PAINT GREEN (-5300 10550);
DISPLAY INVISIBLE (-5300 10550);
FORCEPROP 1 LAST PATH I169
J 0
(-5497 10655);
DISPLAY 1.212766 (-5497 10655);
PAINT GREEN (-5497 10655);
DISPLAY INVISIBLE (-5497 10655);
FORCEPROP 1 LAST TOLERANCE -
J 0
(-5497 10805);
DISPLAY 1.212766 (-5497 10805);
PAINT GREEN (-5497 10805);
DISPLAY INVISIBLE (-5497 10805);
FORCEPROP 1 LAST CLS_PN G155-100R0-J0
J 0
(-5436 10750);
DISPLAY 1.212766 (-5436 10750);
PAINT GREEN (-5436 10750);
DISPLAY INVISIBLE (-5436 10750);
FORCEADD RESISTOR..1
(-5300 10350);
FORCEPROP 1 LAST $LOCATION R473
J 2
(-5500 10350);
DISPLAY 1.212766 (-5500 10350);
PAINT GREEN (-5500 10350);
FORCEPROP 0 LAST CDS_LOCATION R473
J 0
(-5050 10450);
DISPLAY 1.021277 (-5050 10450);
DISPLAY INVISIBLE (-5050 10450);
FORCEPROP 0 LAST $SEC 1
J 0
(-5050 10450);
DISPLAY 0.680851 (-5050 10450);
PAINT MONO (-5050 10450);
DISPLAY INVISIBLE (-5050 10450);
FORCEPROP 0 LAST CDS_SEC 1
J 0
(-5050 10450);
DISPLAY 1.021277 (-5050 10450);
DISPLAY INVISIBLE (-5050 10450);
FORCEPROP 0 LASTPIN (-5400 10350) $PN 1
J 2
(-5410 10360);
DISPLAY 0.680851 (-5410 10360);
PAINT MONO (-5410 10360);
FORCEPROP 0 LASTPIN (-5150 10350) $PN 2
J 0
(-5140 10360);
DISPLAY 0.680851 (-5140 10360);
PAINT MONO (-5140 10360);
FORCEPROP 0 LAST PACKAGE 0402
J 0
(-5350 10350);
DISPLAY 0.638298 (-5350 10350);
FORCEPROP 1 LAST VALUE 0OHM
J 0
(-5061 10355);
DISPLAY 1.212766 (-5061 10355);
PAINT GREEN (-5061 10355);
FORCEPROP 1 LAST CDS_LMAN_SYM_OUTLINE -50,50,100,-50
J 0
(-5300 10350);
DISPLAY 0.468085 (-5300 10350);
PAINT GREEN (-5300 10350);
DISPLAY INVISIBLE (-5300 10350);
FORCEPROP 2 LAST CDS_LIB passive
J 0
(-5300 10350);
DISPLAY INVISIBLE (-5300 10350);
FORCEPROP 1 LAST PATH I170
J 0
(-5497 10455);
DISPLAY 1.212766 (-5497 10455);
PAINT GREEN (-5497 10455);
DISPLAY INVISIBLE (-5497 10455);
FORCEPROP 1 LAST TOLERANCE -
J 0
(-5497 10605);
DISPLAY 1.212766 (-5497 10605);
PAINT GREEN (-5497 10605);
DISPLAY INVISIBLE (-5497 10605);
FORCEPROP 1 LAST CLS_PN G155-100R0-J0
J 0
(-5436 10550);
DISPLAY 1.212766 (-5436 10550);
PAINT GREEN (-5436 10550);
DISPLAY INVISIBLE (-5436 10550);
FORCEADD OFFPAGE_BI..1
(-2850 10450);
FORCEPROP 2 LAST $XR0 24H12<> 
J 0
(-2790 10450);
DISPLAY 0.638298 (-2790 10450);
PAINT MONO (-2790 10450);
FORCEPROP 2 LAST PATH I171
J 2
(-2900 10550);
DISPLAY 1.021277 (-2900 10550);
DISPLAY INVISIBLE (-2900 10550);
FORCEPROP 1 LAST OFFPAGE TRUE
J 0
(-2840 10505);
DISPLAY 0.808511 (-2840 10505);
PAINT GREEN (-2840 10505);
DISPLAY INVISIBLE (-2840 10505);
FORCEPROP 1 LAST BODY_TYPE COMMENT
J 0
(-2840 10585);
DISPLAY 0.808511 (-2840 10585);
PAINT GREEN (-2840 10585);
DISPLAY INVISIBLE (-2840 10585);
FORCEPROP 1 LAST CDS_LMAN_SYM_OUTLINE -50,50,50,-50
J 0
(-2850 10450);
DISPLAY 0.468085 (-2850 10450);
PAINT GREEN (-2850 10450);
DISPLAY INVISIBLE (-2850 10450);
FORCEPROP 2 LAST CDS_LIB cls
J 2
(-2850 10450);
DISPLAY INVISIBLE (-2850 10450);
FORCEADD OFFPAGE_OUT..1
(-2850 10550);
FORCEPROP 2 LAST $XR0 24J12< 
J 0
(-2795 10550);
DISPLAY 0.638298 (-2795 10550);
PAINT MONO (-2795 10550);
FORCEPROP 2 LAST PATH I172
J 0
(-2800 10650);
DISPLAY 1.021277 (-2800 10650);
DISPLAY INVISIBLE (-2800 10650);
FORCEPROP 1 LAST OFFPAGE TRUE
J 0
(-2840 10605);
DISPLAY 0.808511 (-2840 10605);
PAINT GREEN (-2840 10605);
DISPLAY INVISIBLE (-2840 10605);
FORCEPROP 1 LAST BODY_TYPE COMMENT
J 0
(-2840 10685);
DISPLAY 0.808511 (-2840 10685);
PAINT GREEN (-2840 10685);
DISPLAY INVISIBLE (-2840 10685);
FORCEPROP 1 LAST CDS_LMAN_SYM_OUTLINE -50,50,50,-50
J 0
(-2850 10550);
DISPLAY 0.468085 (-2850 10550);
PAINT GREEN (-2850 10550);
DISPLAY INVISIBLE (-2850 10550);
FORCEPROP 2 LAST CDS_LIB cls
J 0
(-2850 10550);
DISPLAY INVISIBLE (-2850 10550);
FORCEADD G200_10283_01..1
(-2650 8850);
FORCEPROP 1 LAST $LOCATION J10
J 0
(-2650 8900);
DISPLAY 1.212766 (-2650 8900);
PAINT GREEN (-2650 8900);
FORCEPROP 0 LAST CDS_LOCATION J10
J 0
(-2700 7600);
DISPLAY 1.212766 (-2700 7600);
PAINT GREEN (-2700 7600);
DISPLAY INVISIBLE (-2700 7600);
FORCEPROP 0 LAST $SEC 1
J 0
(-3150 9050);
DISPLAY 0.680851 (-3150 9050);
PAINT MONO (-3150 9050);
DISPLAY INVISIBLE (-3150 9050);
FORCEPROP 0 LAST CDS_SEC 1
J 0
(-3150 9050);
DISPLAY 1.021277 (-3150 9050);
DISPLAY INVISIBLE (-3150 9050);
FORCEPROP 0 LASTPIN (-2750 8750) $PN 1
J 2
(-2760 8760);
DISPLAY 0.680851 (-2760 8760);
PAINT MONO (-2760 8760);
FORCEPROP 0 LASTPIN (-2050 8750) $PN 2
J 0
(-2040 8760);
DISPLAY 0.680851 (-2040 8760);
PAINT MONO (-2040 8760);
FORCEPROP 0 LASTPIN (-2750 8550) $PN 3
J 2
(-2760 8560);
DISPLAY 0.680851 (-2760 8560);
PAINT MONO (-2760 8560);
FORCEPROP 0 LASTPIN (-2050 8550) $PN 4
J 0
(-2040 8560);
DISPLAY 0.680851 (-2040 8560);
PAINT MONO (-2040 8560);
FORCEPROP 0 LASTPIN (-2750 8350) $PN 5
J 2
(-2760 8360);
DISPLAY 0.680851 (-2760 8360);
PAINT MONO (-2760 8360);
FORCEPROP 0 LASTPIN (-2050 8350) $PN 6
J 0
(-2040 8360);
DISPLAY 0.680851 (-2040 8360);
PAINT MONO (-2040 8360);
FORCEPROP 0 LASTPIN (-2750 8150) $PN 7
J 2
(-2760 8160);
DISPLAY 0.680851 (-2760 8160);
PAINT MONO (-2760 8160);
FORCEPROP 0 LASTPIN (-2050 8150) $PN 8
J 0
(-2040 8160);
DISPLAY 0.680851 (-2040 8160);
PAINT MONO (-2040 8160);
FORCEPROP 0 LASTPIN (-2750 7950) $PN 9
J 2
(-2760 7960);
DISPLAY 0.680851 (-2760 7960);
PAINT MONO (-2760 7960);
FORCEPROP 0 LASTPIN (-2050 7950) $PN 10
J 0
(-2040 7960);
DISPLAY 0.680851 (-2040 7960);
PAINT MONO (-2040 7960);
FORCEPROP 1 LAST CLS_PN G200-10283-01
J 0
(-2650 9100);
DISPLAY 0.978723 (-2650 9100);
PAINT GREEN (-2650 9100);
FORCEPROP 0 LAST PART_NUMBER 95278-101A10LF
J 2
(-1950 9000);
DISPLAY 1.021277 (-1950 9000);
FORCEPROP 2 LAST CDS_LIB connector
J 2
(-2650 8850);
DISPLAY INVISIBLE (-2650 8850);
FORCEPROP 1 LAST CDS_LMAN_SYM_OUTLINE 0,0,500,-1000
J 0
(-2650 8850);
DISPLAY 0.468085 (-2650 8850);
PAINT GREEN (-2650 8850);
DISPLAY INVISIBLE (-2650 8850);
FORCEPROP 1 LAST PATH I173
J 0
(-2600 8900);
DISPLAY 1.212766 (-2600 8900);
PAINT GREEN (-2600 8900);
DISPLAY INVISIBLE (-2600 8900);
FORCEADD OFFPAGE_IN..2
(-900 8150);
FORCEPROP 2 LAST $XR0 22F4> 
J 0
(-845 8150);
DISPLAY 0.638298 (-845 8150);
PAINT MONO (-845 8150);
FORCEPROP 2 LAST PATH I176
J 0
(-800 8200);
DISPLAY 1.021277 (-800 8200);
DISPLAY INVISIBLE (-800 8200);
FORCEPROP 1 LAST OFFPAGE TRUE
J 0
(-890 8205);
DISPLAY 0.808511 (-890 8205);
PAINT GREEN (-890 8205);
DISPLAY INVISIBLE (-890 8205);
FORCEPROP 1 LAST BODY_TYPE COMMENT
J 0
(-890 8285);
DISPLAY 0.808511 (-890 8285);
PAINT GREEN (-890 8285);
DISPLAY INVISIBLE (-890 8285);
FORCEPROP 1 LAST CDS_LMAN_SYM_OUTLINE -50,50,50,-50
J 0
(-900 8150);
DISPLAY 0.468085 (-900 8150);
PAINT GREEN (-900 8150);
DISPLAY INVISIBLE (-900 8150);
FORCEPROP 2 LAST CDS_LIB cls
J 2
(-900 8150);
DISPLAY INVISIBLE (-900 8150);
FORCEADD RESISTOR..2
R 1
(-4200 9000);
FORCEPROP 1 LAST $LOCATION R349
J 0
(-4550 9000);
DISPLAY 1.212766 (-4550 9000);
PAINT GREEN (-4550 9000);
FORCEPROP 0 LAST CDS_LOCATION R349
R 1
J 0
(-4000 9100);
DISPLAY 1.021277 (-4000 9100);
DISPLAY INVISIBLE (-4000 9100);
FORCEPROP 0 LAST $SEC 1
R 1
J 0
(-4000 9100);
DISPLAY 0.680851 (-4000 9100);
PAINT MONO (-4000 9100);
DISPLAY INVISIBLE (-4000 9100);
FORCEPROP 0 LAST CDS_SEC 1
R 1
J 0
(-4000 9100);
DISPLAY 1.021277 (-4000 9100);
DISPLAY INVISIBLE (-4000 9100);
FORCEPROP 0 LASTPIN (-4300 9000) $PN 1
J 2
(-4310 9010);
DISPLAY 0.680851 (-4310 9010);
PAINT MONO (-4310 9010);
FORCEPROP 0 LASTPIN (-4050 9000) $PN 2
J 0
(-4040 9010);
DISPLAY 0.680851 (-4040 9010);
PAINT MONO (-4040 9010);
FORCEPROP 1 LAST VALUE 100KOHM
J 0
(-4000 9000);
DISPLAY 1.212766 (-4000 9000);
PAINT GREEN (-4000 9000);
FORCEPROP 0 LAST PACKAGE 0402
J 0
(-4250 8900);
DISPLAY 0.808511 (-4250 8900);
FORCEPROP 1 LAST TOLERANCE 1%
R 1
J 0
(-4455 8803);
DISPLAY 1.212766 (-4455 8803);
PAINT GREEN (-4455 8803);
DISPLAY INVISIBLE (-4455 8803);
FORCEPROP 1 LAST CLS_PN G155-11003-01
R 1
J 0
(-4400 8864);
DISPLAY 1.212766 (-4400 8864);
PAINT GREEN (-4400 8864);
DISPLAY INVISIBLE (-4400 8864);
FORCEPROP 1 LAST PATH I184
R 1
J 0
(-4305 8803);
DISPLAY 1.212766 (-4305 8803);
PAINT GREEN (-4305 8803);
DISPLAY INVISIBLE (-4305 8803);
FORCEPROP 2 LAST CDS_LIB passive
J 0
(-4200 9000);
DISPLAY INVISIBLE (-4200 9000);
FORCEPROP 1 LAST CDS_LMAN_SYM_OUTLINE -50,50,50,-100
R 1
J 0
(-4200 9000);
DISPLAY 0.468085 (-4200 9000);
PAINT GREEN (-4200 9000);
DISPLAY INVISIBLE (-4200 9000);
FORCEADD RESISTOR..1
(-5300 8750);
FORCEPROP 1 LAST $LOCATION R131
J 2
(-5500 8750);
DISPLAY 1.212766 (-5500 8750);
PAINT GREEN (-5500 8750);
FORCEPROP 0 LAST CDS_LOCATION R131
J 0
(-5100 8850);
DISPLAY 1.021277 (-5100 8850);
DISPLAY INVISIBLE (-5100 8850);
FORCEPROP 0 LAST $SEC 1
J 0
(-5100 8850);
DISPLAY 0.680851 (-5100 8850);
PAINT MONO (-5100 8850);
DISPLAY INVISIBLE (-5100 8850);
FORCEPROP 0 LAST CDS_SEC 1
J 0
(-5100 8850);
DISPLAY 1.021277 (-5100 8850);
DISPLAY INVISIBLE (-5100 8850);
FORCEPROP 0 LASTPIN (-5400 8750) $PN 1
J 2
(-5410 8760);
DISPLAY 0.680851 (-5410 8760);
PAINT MONO (-5410 8760);
FORCEPROP 0 LASTPIN (-5150 8750) $PN 2
J 0
(-5140 8760);
DISPLAY 0.680851 (-5140 8760);
PAINT MONO (-5140 8760);
FORCEPROP 0 LAST PACKAGE 0402
J 0
(-5350 8800);
DISPLAY 0.808511 (-5350 8800);
FORCEPROP 1 LAST VALUE 100OHM
J 0
(-5050 8750);
DISPLAY 1.212766 (-5050 8750);
PAINT GREEN (-5050 8750);
FORCEPROP 1 LAST CLS_PN G155-11000-01
J 0
(-5436 8950);
DISPLAY 1.212766 (-5436 8950);
PAINT GREEN (-5436 8950);
DISPLAY INVISIBLE (-5436 8950);
FORCEPROP 1 LAST TOLERANCE 1%
J 0
(-5497 9005);
DISPLAY 1.212766 (-5497 9005);
PAINT GREEN (-5497 9005);
DISPLAY INVISIBLE (-5497 9005);
FORCEPROP 1 LAST PATH I187
J 0
(-5497 8855);
DISPLAY 1.212766 (-5497 8855);
PAINT GREEN (-5497 8855);
DISPLAY INVISIBLE (-5497 8855);
FORCEPROP 1 LAST CDS_LMAN_SYM_OUTLINE -50,50,100,-50
J 0
(-5300 8750);
DISPLAY 0.468085 (-5300 8750);
PAINT GREEN (-5300 8750);
DISPLAY INVISIBLE (-5300 8750);
FORCEPROP 2 LAST CDS_LIB passive
J 0
(-5300 8750);
DISPLAY INVISIBLE (-5300 8750);
FORCEADD RESISTOR..1
(-5300 8650);
FORCEPROP 1 LAST $LOCATION R132
J 2
(-5500 8650);
DISPLAY 1.212766 (-5500 8650);
PAINT GREEN (-5500 8650);
FORCEPROP 0 LAST CDS_LOCATION R132
J 0
(-5100 8750);
DISPLAY 1.021277 (-5100 8750);
DISPLAY INVISIBLE (-5100 8750);
FORCEPROP 0 LAST $SEC 1
J 0
(-5100 8750);
DISPLAY 0.680851 (-5100 8750);
PAINT MONO (-5100 8750);
DISPLAY INVISIBLE (-5100 8750);
FORCEPROP 0 LAST CDS_SEC 1
J 0
(-5100 8750);
DISPLAY 1.021277 (-5100 8750);
DISPLAY INVISIBLE (-5100 8750);
FORCEPROP 0 LASTPIN (-5400 8650) $PN 1
J 2
(-5410 8660);
DISPLAY 0.680851 (-5410 8660);
PAINT MONO (-5410 8660);
FORCEPROP 0 LASTPIN (-5150 8650) $PN 2
J 0
(-5140 8660);
DISPLAY 0.680851 (-5140 8660);
PAINT MONO (-5140 8660);
FORCEPROP 0 LAST PACKAGE 0402
J 0
(-5350 8550);
DISPLAY 0.808511 (-5350 8550);
FORCEPROP 1 LAST VALUE 100OHM
J 0
(-5050 8650);
DISPLAY 1.212766 (-5050 8650);
PAINT GREEN (-5050 8650);
FORCEPROP 1 LAST PATH I188
J 0
(-5497 8755);
DISPLAY 1.212766 (-5497 8755);
PAINT GREEN (-5497 8755);
DISPLAY INVISIBLE (-5497 8755);
FORCEPROP 1 LAST TOLERANCE 1%
J 0
(-5497 8905);
DISPLAY 1.212766 (-5497 8905);
PAINT GREEN (-5497 8905);
DISPLAY INVISIBLE (-5497 8905);
FORCEPROP 1 LAST CLS_PN G155-11000-01
J 0
(-5436 8850);
DISPLAY 1.212766 (-5436 8850);
PAINT GREEN (-5436 8850);
DISPLAY INVISIBLE (-5436 8850);
FORCEPROP 1 LAST CDS_LMAN_SYM_OUTLINE -50,50,100,-50
J 0
(-5300 8650);
DISPLAY 0.468085 (-5300 8650);
PAINT GREEN (-5300 8650);
DISPLAY INVISIBLE (-5300 8650);
FORCEPROP 2 LAST CDS_LIB passive
J 0
(-5300 8650);
DISPLAY INVISIBLE (-5300 8650);
FORCEADD RESISTOR..2
R 1
(-4200 10100);
FORCEPROP 1 LAST $LOCATION R478
J 0
(-4550 10100);
DISPLAY 1.212766 (-4550 10100);
PAINT GREEN (-4550 10100);
FORCEPROP 0 LAST CDS_LOCATION R478
R 1
J 0
(-4000 10200);
DISPLAY 1.021277 (-4000 10200);
DISPLAY INVISIBLE (-4000 10200);
FORCEPROP 0 LAST $SEC 1
R 1
J 0
(-4000 10200);
DISPLAY 0.680851 (-4000 10200);
PAINT MONO (-4000 10200);
DISPLAY INVISIBLE (-4000 10200);
FORCEPROP 0 LAST CDS_SEC 1
R 1
J 0
(-4000 10200);
DISPLAY 1.021277 (-4000 10200);
DISPLAY INVISIBLE (-4000 10200);
FORCEPROP 0 LASTPIN (-4300 10100) $PN 1
J 2
(-4310 10110);
DISPLAY 0.680851 (-4310 10110);
PAINT MONO (-4310 10110);
FORCEPROP 0 LASTPIN (-4050 10100) $PN 2
J 0
(-4040 10110);
DISPLAY 0.680851 (-4040 10110);
PAINT MONO (-4040 10110);
FORCEPROP 0 LAST PACKAGE 0402
J 0
(-4250 10150);
DISPLAY 0.808511 (-4250 10150);
FORCEPROP 1 LAST VALUE 100KOHM
J 0
(-4000 10100);
DISPLAY 1.212766 (-4000 10100);
PAINT GREEN (-4000 10100);
FORCEPROP 1 LAST CLS_PN G155-11003-01
R 1
J 0
(-4400 9964);
DISPLAY 1.212766 (-4400 9964);
PAINT GREEN (-4400 9964);
DISPLAY INVISIBLE (-4400 9964);
FORCEPROP 1 LAST CDS_LMAN_SYM_OUTLINE -50,50,50,-100
R 1
J 0
(-4200 10100);
DISPLAY 0.468085 (-4200 10100);
PAINT GREEN (-4200 10100);
DISPLAY INVISIBLE (-4200 10100);
FORCEPROP 2 LAST CDS_LIB passive
J 0
(-4200 10100);
DISPLAY INVISIBLE (-4200 10100);
FORCEPROP 1 LAST TOLERANCE 1%
R 1
J 0
(-4455 9903);
DISPLAY 1.212766 (-4455 9903);
PAINT GREEN (-4455 9903);
DISPLAY INVISIBLE (-4455 9903);
FORCEPROP 1 LAST PATH I190
R 1
J 0
(-4305 9903);
DISPLAY 1.212766 (-4305 9903);
PAINT GREEN (-4305 9903);
DISPLAY INVISIBLE (-4305 9903);
FORCEADD RESISTOR..2
R 1
(-4200 10000);
FORCEPROP 1 LAST $LOCATION R479
J 0
(-4550 10000);
DISPLAY 1.212766 (-4550 10000);
PAINT GREEN (-4550 10000);
FORCEPROP 0 LAST CDS_LOCATION R479
R 1
J 0
(-4000 10100);
DISPLAY 1.021277 (-4000 10100);
DISPLAY INVISIBLE (-4000 10100);
FORCEPROP 0 LAST $SEC 1
R 1
J 0
(-4000 10100);
DISPLAY 0.680851 (-4000 10100);
PAINT MONO (-4000 10100);
DISPLAY INVISIBLE (-4000 10100);
FORCEPROP 0 LAST CDS_SEC 1
R 1
J 0
(-4000 10100);
DISPLAY 1.021277 (-4000 10100);
DISPLAY INVISIBLE (-4000 10100);
FORCEPROP 0 LASTPIN (-4300 10000) $PN 1
J 2
(-4310 10010);
DISPLAY 0.680851 (-4310 10010);
PAINT MONO (-4310 10010);
FORCEPROP 0 LASTPIN (-4050 10000) $PN 2
J 0
(-4040 10010);
DISPLAY 0.680851 (-4040 10010);
PAINT MONO (-4040 10010);
FORCEPROP 1 LAST VALUE 100KOHM
J 0
(-4000 10000);
DISPLAY 1.212766 (-4000 10000);
PAINT GREEN (-4000 10000);
FORCEPROP 0 LAST PACKAGE 0402
J 0
(-4250 9950);
DISPLAY 0.808511 (-4250 9950);
FORCEPROP 1 LAST CLS_PN G155-11003-01
R 1
J 0
(-4400 9864);
DISPLAY 1.212766 (-4400 9864);
PAINT GREEN (-4400 9864);
DISPLAY INVISIBLE (-4400 9864);
FORCEPROP 1 LAST CDS_LMAN_SYM_OUTLINE -50,50,50,-100
R 1
J 0
(-4200 10000);
DISPLAY 0.468085 (-4200 10000);
PAINT GREEN (-4200 10000);
DISPLAY INVISIBLE (-4200 10000);
FORCEPROP 2 LAST CDS_LIB passive
J 0
(-4200 10000);
DISPLAY INVISIBLE (-4200 10000);
FORCEPROP 1 LAST TOLERANCE 1%
R 1
J 0
(-4455 9803);
DISPLAY 1.212766 (-4455 9803);
PAINT GREEN (-4455 9803);
DISPLAY INVISIBLE (-4455 9803);
FORCEPROP 1 LAST PATH I191
R 1
J 0
(-4305 9803);
DISPLAY 1.212766 (-4305 9803);
PAINT GREEN (-4305 9803);
DISPLAY INVISIBLE (-4305 9803);
FORCEADD OFFPAGE_IN..2
(-900 8350);
FORCEPROP 2 LAST $XR0 21J6> 
J 0
(-845 8350);
DISPLAY 0.638298 (-845 8350);
PAINT MONO (-845 8350);
FORCEPROP 2 LAST PATH I195
J 0
(-800 8400);
DISPLAY 1.021277 (-800 8400);
DISPLAY INVISIBLE (-800 8400);
FORCEPROP 1 LAST OFFPAGE TRUE
J 0
(-890 8405);
DISPLAY 0.808511 (-890 8405);
PAINT GREEN (-890 8405);
DISPLAY INVISIBLE (-890 8405);
FORCEPROP 2 LAST CDS_LIB cls
J 0
(-900 8350);
DISPLAY INVISIBLE (-900 8350);
FORCEPROP 1 LAST CDS_LMAN_SYM_OUTLINE -50,50,50,-50
J 0
(-900 8350);
DISPLAY 0.468085 (-900 8350);
PAINT GREEN (-900 8350);
DISPLAY INVISIBLE (-900 8350);
FORCEPROP 1 LAST BODY_TYPE COMMENT
J 0
(-890 8485);
DISPLAY 0.808511 (-890 8485);
PAINT GREEN (-890 8485);
DISPLAY INVISIBLE (-890 8485);
FORCEADD OFFPAGE_OUT..1
(-900 8550);
FORCEPROP 2 LAST $XR0 22F4< 
J 0
(-845 8550);
DISPLAY 0.638298 (-845 8550);
PAINT MONO (-845 8550);
FORCEPROP 1 LAST CDS_LMAN_SYM_OUTLINE -50,50,50,-50
J 0
(-900 8550);
DISPLAY 0.468085 (-900 8550);
PAINT GREEN (-900 8550);
DISPLAY INVISIBLE (-900 8550);
FORCEPROP 2 LAST CDS_LIB cls
J 0
(-900 8550);
DISPLAY INVISIBLE (-900 8550);
FORCEPROP 2 LAST PATH I196
J 0
(-850 8650);
DISPLAY 1.021277 (-850 8650);
DISPLAY INVISIBLE (-850 8650);
FORCEPROP 1 LAST OFFPAGE TRUE
J 0
(-890 8605);
DISPLAY 0.808511 (-890 8605);
PAINT GREEN (-890 8605);
DISPLAY INVISIBLE (-890 8605);
FORCEPROP 1 LAST BODY_TYPE COMMENT
J 0
(-890 8685);
DISPLAY 0.808511 (-890 8685);
PAINT GREEN (-890 8685);
DISPLAY INVISIBLE (-890 8685);
FORCEADD OFFPAGE_OUT..1
(-900 8750);
FORCEPROP 2 LAST $XR0 21J6< 
J 0
(-845 8750);
DISPLAY 0.638298 (-845 8750);
PAINT MONO (-845 8750);
FORCEPROP 2 LAST PATH I197
J 0
(-850 8850);
DISPLAY 1.021277 (-850 8850);
DISPLAY INVISIBLE (-850 8850);
FORCEPROP 1 LAST OFFPAGE TRUE
J 0
(-890 8805);
DISPLAY 0.808511 (-890 8805);
PAINT GREEN (-890 8805);
DISPLAY INVISIBLE (-890 8805);
FORCEPROP 1 LAST BODY_TYPE COMMENT
J 0
(-890 8885);
DISPLAY 0.808511 (-890 8885);
PAINT GREEN (-890 8885);
DISPLAY INVISIBLE (-890 8885);
FORCEPROP 1 LAST CDS_LMAN_SYM_OUTLINE -50,50,50,-50
J 0
(-900 8750);
DISPLAY 0.468085 (-900 8750);
PAINT GREEN (-900 8750);
DISPLAY INVISIBLE (-900 8750);
FORCEPROP 2 LAST CDS_LIB cls
J 0
(-900 8750);
DISPLAY INVISIBLE (-900 8750);
FORCEADD RESISTOR..2
R 1
(-5300 11600);
FORCEPROP 1 LAST $LOCATION R466
J 0
(-5700 11600);
DISPLAY 1.212766 (-5700 11600);
PAINT GREEN (-5700 11600);
FORCEPROP 0 LAST CDS_LOCATION R466
R 1
J 0
(-5050 11700);
DISPLAY 1.021277 (-5050 11700);
DISPLAY INVISIBLE (-5050 11700);
FORCEPROP 0 LAST $SEC 1
R 1
J 0
(-5050 11700);
DISPLAY 0.680851 (-5050 11700);
PAINT MONO (-5050 11700);
DISPLAY INVISIBLE (-5050 11700);
FORCEPROP 0 LAST CDS_SEC 1
R 1
J 0
(-5050 11700);
DISPLAY 1.021277 (-5050 11700);
DISPLAY INVISIBLE (-5050 11700);
FORCEPROP 0 LASTPIN (-5400 11600) $PN 1
J 2
(-5410 11610);
DISPLAY 0.680851 (-5410 11610);
PAINT MONO (-5410 11610);
FORCEPROP 0 LASTPIN (-5150 11600) $PN 2
J 0
(-5140 11610);
DISPLAY 0.680851 (-5140 11610);
PAINT MONO (-5140 11610);
FORCEPROP 1 LAST VALUE 100KOHM
J 0
(-5050 11600);
DISPLAY 1.212766 (-5050 11600);
PAINT GREEN (-5050 11600);
FORCEPROP 0 LAST PACKAGE 0402
J 0
(-5350 11650);
DISPLAY 0.808511 (-5350 11650);
FORCEPROP 1 LAST PATH I198
R 1
J 0
(-5405 11403);
DISPLAY 1.212766 (-5405 11403);
PAINT GREEN (-5405 11403);
DISPLAY INVISIBLE (-5405 11403);
FORCEPROP 1 LAST TOLERANCE 1%
R 1
J 0
(-5555 11403);
DISPLAY 1.212766 (-5555 11403);
PAINT GREEN (-5555 11403);
DISPLAY INVISIBLE (-5555 11403);
FORCEPROP 1 LAST CLS_PN G155-11003-01
R 1
J 0
(-5500 11464);
DISPLAY 1.212766 (-5500 11464);
PAINT GREEN (-5500 11464);
DISPLAY INVISIBLE (-5500 11464);
FORCEPROP 1 LAST CDS_LMAN_SYM_OUTLINE -50,50,50,-100
R 1
J 0
(-5300 11600);
DISPLAY 0.468085 (-5300 11600);
PAINT GREEN (-5300 11600);
DISPLAY INVISIBLE (-5300 11600);
FORCEPROP 2 LAST CDS_LIB passive
J 0
(-5300 11600);
DISPLAY INVISIBLE (-5300 11600);
FORCEADD CAT93C46VI_GT3_SOIC8..1
R 2
(-12050 7550);
FORCEPROP 1 LAST $LOCATION U31
J 2
(-12400 7700);
DISPLAY 1.212766 (-12400 7700);
PAINT GREEN (-12400 7700);
FORCEPROP 0 LAST CDS_LOCATION U31
J 0
(-12400 7800);
DISPLAY 1.021277 (-12400 7800);
DISPLAY INVISIBLE (-12400 7800);
FORCEPROP 0 LAST $SEC 1
J 0
(-12400 7800);
DISPLAY 0.680851 (-12400 7800);
PAINT MONO (-12400 7800);
DISPLAY INVISIBLE (-12400 7800);
FORCEPROP 0 LAST CDS_SEC 1
J 0
(-12400 7800);
DISPLAY 1.021277 (-12400 7800);
DISPLAY INVISIBLE (-12400 7800);
FORCEPROP 0 LASTPIN (-11950 7350) $PN 1
J 0
(-11940 7360);
DISPLAY 0.680851 (-11940 7360);
PAINT MONO (-11940 7360);
FORCEPROP 0 LASTPIN (-11950 7150) $PN 3
J 0
(-11940 7160);
DISPLAY 0.680851 (-11940 7160);
PAINT MONO (-11940 7160);
FORCEPROP 0 LASTPIN (-12650 7450) $PN 4
J 2
(-12660 7460);
DISPLAY 0.680851 (-12660 7460);
PAINT MONO (-12660 7460);
FORCEPROP 0 LASTPIN (-12650 7150) $PN 7
J 2
(-12660 7160);
DISPLAY 0.680851 (-12660 7160);
PAINT MONO (-12660 7160);
FORCEPROP 0 LASTPIN (-11950 7450) $PN 6
J 0
(-11940 7460);
DISPLAY 0.680851 (-11940 7460);
PAINT MONO (-11940 7460);
FORCEPROP 0 LASTPIN (-11950 7250) $PN 2
J 0
(-11940 7260);
DISPLAY 0.680851 (-11940 7260);
PAINT MONO (-11940 7260);
FORCEPROP 1 LAST CLS_PN G221-10075-01
J 2
(-11800 7600);
DISPLAY 1.212766 (-11800 7600);
PAINT GREEN (-11800 7600);
FORCEPROP 2 LAST CDS_LIB memory
J 2
(-12050 7550);
DISPLAY INVISIBLE (-12050 7550);
FORCEPROP 1 LAST CDS_LMAN_SYM_OUTLINE 0,0,500,-500
J 2
(-12050 7550);
DISPLAY 0.468085 (-12050 7550);
PAINT GREEN (-12050 7550);
DISPLAY INVISIBLE (-12050 7550);
FORCEPROP 1 LAST PATH I200
J 2
(-12100 7600);
DISPLAY 1.212766 (-12100 7600);
PAINT GREEN (-12100 7600);
DISPLAY INVISIBLE (-12100 7600);
FORCEADD CAT93C46VI_GT3_SOIC8..2
(-13700 7700);
FORCEPROP 1 LAST $LOCATION U31
J 2
(-13650 6900);
DISPLAY 1.212766 (-13650 6900);
PAINT GREEN (-13650 6900);
FORCEPROP 0 LAST CDS_LOCATION U31
J 0
(-13650 7000);
DISPLAY 1.021277 (-13650 7000);
DISPLAY INVISIBLE (-13650 7000);
FORCEPROP 0 LAST $SEC 2
J 0
(-13650 7000);
DISPLAY 0.680851 (-13650 7000);
PAINT MONO (-13650 7000);
DISPLAY INVISIBLE (-13650 7000);
FORCEPROP 0 LAST CDS_SEC 2
J 0
(-13650 7000);
DISPLAY 1.021277 (-13650 7000);
DISPLAY INVISIBLE (-13650 7000);
FORCEPROP 0 LASTPIN (-13500 7100) $PN 5
R 1
J 2
(-13510 7090);
DISPLAY 0.680851 (-13510 7090);
PAINT MONO (-13510 7090);
FORCEPROP 0 LASTPIN (-13500 7800) $PN 8
R 1
J 0
(-13510 7810);
DISPLAY 0.680851 (-13510 7810);
PAINT MONO (-13510 7810);
FORCEPROP 1 LAST CLS_PN G221-10075-01
J 2
(-13650 6800);
DISPLAY 1.212766 (-13650 6800);
PAINT GREEN (-13650 6800);
FORCEPROP 1 LAST CDS_LMAN_SYM_OUTLINE 0,0,400,-500
J 0
(-13700 7700);
DISPLAY 0.468085 (-13700 7700);
PAINT GREEN (-13700 7700);
DISPLAY INVISIBLE (-13700 7700);
FORCEPROP 2 LAST CDS_LIB memory
J 0
(-13700 7700);
DISPLAY INVISIBLE (-13700 7700);
FORCEPROP 1 LAST PATH I201
J 2
(-13750 7750);
DISPLAY 1.212766 (-13750 7750);
PAINT GREEN (-13750 7750);
DISPLAY INVISIBLE (-13750 7750);
FORCEADD GND_SG..1
(-13550 6850);
FORCEPROP 3 LASTPIN (-13500 6900) SIG_NAME SG\g
J 0
(-13490 6910);
DISPLAY 0.659574 (-13490 6910);
PAINT MONO (-13490 6910);
DISPLAY INVISIBLE (-13490 6910);
FORCEPROP 1 LAST HDL_POWER SG
J 1
(-13495 6755);
DISPLAY 0.808511 (-13495 6755);
PAINT GREEN (-13495 6755);
FORCEPROP 1 LAST PATH I204
J 0
(-13515 6850);
DISPLAY 0.808511 (-13515 6850);
PAINT GREEN (-13515 6850);
DISPLAY INVISIBLE (-13515 6850);
FORCEPROP 1 LAST BODY_TYPE PLUMBING
J 0
(-13535 6835);
DISPLAY 0.808511 (-13535 6835);
PAINT GREEN (-13535 6835);
DISPLAY INVISIBLE (-13535 6835);
FORCEPROP 2 LAST CDS_LIB cls
J 0
(-13550 6850);
DISPLAY INVISIBLE (-13550 6850);
FORCEPROP 1 LAST CDS_LMAN_SYM_OUTLINE 0,0,100,-50
J 0
(-13550 6850);
DISPLAY 0.468085 (-13550 6850);
PAINT GREEN (-13550 6850);
DISPLAY INVISIBLE (-13550 6850);
FORCEADD RESISTOR..1
(-12350 7950);
FORCEPROP 1 LAST $LOCATION R447
J 2
(-12550 7950);
DISPLAY 1.212766 (-12550 7950);
PAINT GREEN (-12550 7950);
FORCEPROP 0 LAST CDS_LOCATION R447
J 0
(-12100 8050);
DISPLAY 1.021277 (-12100 8050);
DISPLAY INVISIBLE (-12100 8050);
FORCEPROP 0 LAST $SEC 1
J 0
(-12100 8050);
DISPLAY 0.680851 (-12100 8050);
PAINT MONO (-12100 8050);
DISPLAY INVISIBLE (-12100 8050);
FORCEPROP 0 LAST CDS_SEC 1
J 0
(-12100 8050);
DISPLAY 1.021277 (-12100 8050);
DISPLAY INVISIBLE (-12100 8050);
FORCEPROP 0 LASTPIN (-12450 7950) $PN 1
J 2
(-12460 7960);
DISPLAY 0.680851 (-12460 7960);
PAINT MONO (-12460 7960);
FORCEPROP 0 LASTPIN (-12200 7950) $PN 2
J 0
(-12190 7960);
DISPLAY 0.680851 (-12190 7960);
PAINT MONO (-12190 7960);
FORCEPROP 1 LAST VALUE 10KOHM
J 0
(-12100 7950);
DISPLAY 1.212766 (-12100 7950);
PAINT GREEN (-12100 7950);
FORCEPROP 0 LAST PACKAGE 0402
J 0
(-12400 7950);
DISPLAY 1.021277 (-12400 7950);
FORCEPROP 1 LAST CLS_PN G155-11002-01
J 0
(-12486 8150);
DISPLAY 1.212766 (-12486 8150);
PAINT GREEN (-12486 8150);
DISPLAY INVISIBLE (-12486 8150);
FORCEPROP 2 LAST CDS_LIB passive
J 0
(-12350 7950);
DISPLAY INVISIBLE (-12350 7950);
FORCEPROP 1 LAST CDS_LMAN_SYM_OUTLINE -50,50,100,-50
J 0
(-12350 7950);
DISPLAY 0.468085 (-12350 7950);
PAINT GREEN (-12350 7950);
DISPLAY INVISIBLE (-12350 7950);
FORCEPROP 1 LAST TOLERANCE 1%
J 0
(-12547 8205);
DISPLAY 1.212766 (-12547 8205);
PAINT GREEN (-12547 8205);
DISPLAY INVISIBLE (-12547 8205);
FORCEPROP 1 LAST PATH I206
J 0
(-12547 8055);
DISPLAY 1.212766 (-12547 8055);
PAINT GREEN (-12547 8055);
DISPLAY INVISIBLE (-12547 8055);
FORCEADD RESISTOR..1
(-12350 8050);
FORCEPROP 1 LAST $LOCATION R446
J 2
(-12550 8050);
DISPLAY 1.212766 (-12550 8050);
PAINT GREEN (-12550 8050);
FORCEPROP 0 LAST CDS_LOCATION R446
J 0
(-12100 8150);
DISPLAY 1.021277 (-12100 8150);
DISPLAY INVISIBLE (-12100 8150);
FORCEPROP 0 LAST $SEC 1
J 0
(-12100 8150);
DISPLAY 0.680851 (-12100 8150);
PAINT MONO (-12100 8150);
DISPLAY INVISIBLE (-12100 8150);
FORCEPROP 0 LAST CDS_SEC 1
J 0
(-12100 8150);
DISPLAY 1.021277 (-12100 8150);
DISPLAY INVISIBLE (-12100 8150);
FORCEPROP 0 LASTPIN (-12450 8050) $PN 1
J 2
(-12460 8060);
DISPLAY 0.680851 (-12460 8060);
PAINT MONO (-12460 8060);
FORCEPROP 0 LASTPIN (-12200 8050) $PN 2
J 0
(-12190 8060);
DISPLAY 0.680851 (-12190 8060);
PAINT MONO (-12190 8060);
FORCEPROP 1 LAST VALUE 10KOHM
J 0
(-12100 8050);
DISPLAY 1.212766 (-12100 8050);
PAINT GREEN (-12100 8050);
FORCEPROP 0 LAST PACKAGE 0402
J 0
(-12400 8100);
DISPLAY 1.021277 (-12400 8100);
FORCEPROP 1 LAST TOLERANCE 1%
J 0
(-12547 8305);
DISPLAY 1.212766 (-12547 8305);
PAINT GREEN (-12547 8305);
DISPLAY INVISIBLE (-12547 8305);
FORCEPROP 1 LAST CDS_LMAN_SYM_OUTLINE -50,50,100,-50
J 0
(-12350 8050);
DISPLAY 0.468085 (-12350 8050);
PAINT GREEN (-12350 8050);
DISPLAY INVISIBLE (-12350 8050);
FORCEPROP 2 LAST CDS_LIB passive
J 0
(-12350 8050);
DISPLAY INVISIBLE (-12350 8050);
FORCEPROP 1 LAST CLS_PN G155-11002-01
J 0
(-12486 8250);
DISPLAY 1.212766 (-12486 8250);
PAINT GREEN (-12486 8250);
DISPLAY INVISIBLE (-12486 8250);
FORCEPROP 1 LAST PATH I207
J 0
(-12547 8155);
DISPLAY 1.212766 (-12547 8155);
PAINT GREEN (-12547 8155);
DISPLAY INVISIBLE (-12547 8155);
FORCEADD RESISTOR..2
(-13100 7550);
FORCEPROP 1 LAST $LOCATION R444
J 0
(-13050 7400);
DISPLAY 1.212766 (-13050 7400);
PAINT GREEN (-13050 7400);
FORCEPROP 0 LAST CDS_LOCATION R444
J 0
(-13050 7650);
DISPLAY 1.021277 (-13050 7650);
DISPLAY INVISIBLE (-13050 7650);
FORCEPROP 0 LAST $SEC 1
J 0
(-13050 7650);
DISPLAY 0.680851 (-13050 7650);
PAINT MONO (-13050 7650);
DISPLAY INVISIBLE (-13050 7650);
FORCEPROP 0 LAST CDS_SEC 1
J 0
(-13050 7650);
DISPLAY 1.021277 (-13050 7650);
DISPLAY INVISIBLE (-13050 7650);
FORCEPROP 0 LASTPIN (-13100 7650) $PN 1
R 1
J 0
(-13110 7660);
DISPLAY 0.680851 (-13110 7660);
PAINT MONO (-13110 7660);
FORCEPROP 0 LASTPIN (-13100 7400) $PN 2
R 1
J 2
(-13110 7390);
DISPLAY 0.680851 (-13110 7390);
PAINT MONO (-13110 7390);
FORCEPROP 0 LAST PACKAGE 0402
J 0
(-13050 7600);
DISPLAY 1.021277 (-13050 7600);
FORCEPROP 1 LAST VALUE 10KOHM
J 0
(-13050 7500);
DISPLAY 0.978723 (-13050 7500);
PAINT GREEN (-13050 7500);
FORCEPROP 1 LAST CLS_PN G155-11002-01
J 0
(-13236 7750);
DISPLAY 1.212766 (-13236 7750);
PAINT GREEN (-13236 7750);
DISPLAY INVISIBLE (-13236 7750);
FORCEPROP 2 LAST CDS_LIB passive
J 0
(-13100 7550);
DISPLAY INVISIBLE (-13100 7550);
FORCEPROP 1 LAST CDS_LMAN_SYM_OUTLINE -50,50,50,-100
J 0
(-13100 7550);
DISPLAY 0.468085 (-13100 7550);
PAINT GREEN (-13100 7550);
DISPLAY INVISIBLE (-13100 7550);
FORCEPROP 1 LAST TOLERANCE 1%
J 0
(-13297 7805);
DISPLAY 1.212766 (-13297 7805);
PAINT GREEN (-13297 7805);
DISPLAY INVISIBLE (-13297 7805);
FORCEPROP 1 LAST PATH I208
J 0
(-13297 7655);
DISPLAY 1.212766 (-13297 7655);
PAINT GREEN (-13297 7655);
DISPLAY INVISIBLE (-13297 7655);
FORCEADD RESISTOR..2
(-8950 8150);
FORCEPROP 1 LAST $LOCATION R130
J 0
(-9350 8150);
DISPLAY 1.212766 (-9350 8150);
PAINT GREEN (-9350 8150);
FORCEPROP 0 LAST CDS_LOCATION R130
J 0
(-8850 8250);
DISPLAY 1.021277 (-8850 8250);
DISPLAY INVISIBLE (-8850 8250);
FORCEPROP 0 LAST $SEC 1
J 0
(-8850 8250);
DISPLAY 0.680851 (-8850 8250);
PAINT MONO (-8850 8250);
DISPLAY INVISIBLE (-8850 8250);
FORCEPROP 0 LAST CDS_SEC 1
J 0
(-8850 8250);
DISPLAY 1.021277 (-8850 8250);
DISPLAY INVISIBLE (-8850 8250);
FORCEPROP 0 LASTPIN (-8950 8250) $PN 1
R 1
J 0
(-8960 8260);
DISPLAY 0.680851 (-8960 8260);
PAINT MONO (-8960 8260);
FORCEPROP 0 LASTPIN (-8950 8000) $PN 2
R 1
J 2
(-8960 7990);
DISPLAY 0.680851 (-8960 7990);
PAINT MONO (-8960 7990);
FORCEPROP 0 LAST PACKAGE 0402
J 0
(-9350 8250);
DISPLAY 1.021277 (-9350 8250);
FORCEPROP 1 LAST VALUE 10KOHM
J 0
(-9350 8050);
DISPLAY 1.212766 (-9350 8050);
PAINT GREEN (-9350 8050);
FORCEPROP 1 LAST CLS_PN G155-11002-01
J 0
(-9086 8350);
DISPLAY 1.212766 (-9086 8350);
PAINT GREEN (-9086 8350);
DISPLAY INVISIBLE (-9086 8350);
FORCEPROP 1 LAST CDS_LMAN_SYM_OUTLINE -50,50,50,-100
J 0
(-8950 8150);
DISPLAY 0.468085 (-8950 8150);
PAINT GREEN (-8950 8150);
DISPLAY INVISIBLE (-8950 8150);
FORCEPROP 2 LAST CDS_LIB passive
R 3
J 0
(-8950 8150);
DISPLAY INVISIBLE (-8950 8150);
FORCEPROP 1 LAST TOLERANCE 1%
J 0
(-9147 8405);
DISPLAY 1.212766 (-9147 8405);
PAINT GREEN (-9147 8405);
DISPLAY INVISIBLE (-9147 8405);
FORCEPROP 1 LAST PATH I23
J 0
(-9147 8255);
DISPLAY 1.212766 (-9147 8255);
PAINT GREEN (-9147 8255);
DISPLAY INVISIBLE (-9147 8255);
FORCEADD GND_SG..1
(-9000 7600);
FORCEPROP 3 LASTPIN (-8950 7650) SIG_NAME SG\g
J 0
(-8940 7660);
DISPLAY 0.659574 (-8940 7660);
PAINT MONO (-8940 7660);
DISPLAY INVISIBLE (-8940 7660);
FORCEPROP 1 LAST HDL_POWER SG
J 1
(-8945 7505);
DISPLAY 0.808511 (-8945 7505);
PAINT GREEN (-8945 7505);
FORCEPROP 2 LAST CDS_LIB cls
J 0
(-9000 7600);
DISPLAY INVISIBLE (-9000 7600);
FORCEPROP 1 LAST CDS_LMAN_SYM_OUTLINE 0,0,100,-50
J 0
(-9000 7600);
DISPLAY 0.468085 (-9000 7600);
PAINT GREEN (-9000 7600);
DISPLAY INVISIBLE (-9000 7600);
FORCEPROP 1 LAST BODY_TYPE PLUMBING
J 0
(-8985 7585);
DISPLAY 0.808511 (-8985 7585);
PAINT GREEN (-8985 7585);
DISPLAY INVISIBLE (-8985 7585);
FORCEPROP 1 LAST PATH I25
J 0
(-8965 7600);
DISPLAY 0.808511 (-8965 7600);
PAINT GREEN (-8965 7600);
DISPLAY INVISIBLE (-8965 7600);
FORCEADD RESISTOR..1
(-9300 9750);
FORCEPROP 1 LAST $LOCATION R129
J 2
(-9550 9750);
DISPLAY 1.212766 (-9550 9750);
PAINT GREEN (-9550 9750);
FORCEPROP 0 LAST CDS_LOCATION R129
J 0
(-9050 9850);
DISPLAY 1.021277 (-9050 9850);
DISPLAY INVISIBLE (-9050 9850);
FORCEPROP 0 LAST $SEC 1
J 0
(-9050 9850);
DISPLAY 0.680851 (-9050 9850);
PAINT MONO (-9050 9850);
DISPLAY INVISIBLE (-9050 9850);
FORCEPROP 0 LAST CDS_SEC 1
J 0
(-9050 9850);
DISPLAY 1.021277 (-9050 9850);
DISPLAY INVISIBLE (-9050 9850);
FORCEPROP 0 LASTPIN (-9400 9750) $PN 1
J 2
(-9410 9760);
DISPLAY 0.680851 (-9410 9760);
PAINT MONO (-9410 9760);
FORCEPROP 0 LASTPIN (-9150 9750) $PN 2
J 0
(-9140 9760);
DISPLAY 0.680851 (-9140 9760);
PAINT MONO (-9140 9760);
FORCEPROP 1 LAST VALUE 0OHM
J 0
(-9050 9750);
DISPLAY 1.212766 (-9050 9750);
PAINT GREEN (-9050 9750);
FORCEPROP 0 LAST PACKAGE 0402
J 0
(-9350 9650);
DISPLAY 1.021277 (-9350 9650);
FORCEPROP 1 LAST PATH I26
J 0
(-9497 9855);
DISPLAY 1.212766 (-9497 9855);
PAINT GREEN (-9497 9855);
DISPLAY INVISIBLE (-9497 9855);
FORCEPROP 1 LAST CLS_PN G155-100R0-J0
J 0
(-9436 9950);
DISPLAY 1.212766 (-9436 9950);
PAINT GREEN (-9436 9950);
DISPLAY INVISIBLE (-9436 9950);
FORCEPROP 1 LAST TOLERANCE -
J 0
(-9497 10005);
DISPLAY 1.212766 (-9497 10005);
PAINT GREEN (-9497 10005);
DISPLAY INVISIBLE (-9497 10005);
FORCEPROP 1 LAST CDS_LMAN_SYM_OUTLINE -50,50,100,-50
J 0
(-9300 9750);
DISPLAY 0.468085 (-9300 9750);
PAINT GREEN (-9300 9750);
DISPLAY INVISIBLE (-9300 9750);
FORCEPROP 2 LAST CDS_LIB passive
J 0
(-9300 9750);
DISPLAY INVISIBLE (-9300 9750);
FORCEADD RESISTOR..2
R 1
(-9600 9350);
FORCEPROP 1 LAST $LOCATION R18
J 0
(-9950 9350);
DISPLAY 1.212766 (-9950 9350);
PAINT GREEN (-9950 9350);
FORCEPROP 0 LAST CDS_LOCATION R18
J 0
(-10050 9350);
DISPLAY 1.212766 (-10050 9350);
PAINT GREEN (-10050 9350);
DISPLAY INVISIBLE (-10050 9350);
FORCEPROP 0 LAST $SEC 1
R 1
J 0
(-9400 9450);
DISPLAY 0.680851 (-9400 9450);
PAINT MONO (-9400 9450);
DISPLAY INVISIBLE (-9400 9450);
FORCEPROP 0 LAST CDS_SEC 1
R 1
J 0
(-9400 9450);
DISPLAY 1.021277 (-9400 9450);
DISPLAY INVISIBLE (-9400 9450);
FORCEPROP 0 LASTPIN (-9700 9350) $PN 1
J 2
(-9710 9360);
DISPLAY 0.680851 (-9710 9360);
PAINT MONO (-9710 9360);
FORCEPROP 0 LASTPIN (-9450 9350) $PN 2
J 0
(-9440 9360);
DISPLAY 0.680851 (-9440 9360);
PAINT MONO (-9440 9360);
FORCEPROP 0 LAST PACKAGE 0402
J 0
(-9650 9400);
DISPLAY 1.021277 (-9650 9400);
FORCEPROP 1 LAST VALUE 4.7KOHM
J 0
(-9400 9400);
DISPLAY 1.212766 (-9400 9400);
PAINT GREEN (-9400 9400);
FORCEPROP 1 LAST CDS_LMAN_SYM_OUTLINE -50,50,50,-100
R 1
J 0
(-9600 9350);
DISPLAY 0.468085 (-9600 9350);
PAINT GREEN (-9600 9350);
DISPLAY INVISIBLE (-9600 9350);
FORCEPROP 2 LAST CDS_LIB passive
J 0
(-9600 9350);
DISPLAY INVISIBLE (-9600 9350);
FORCEPROP 1 LAST PATH I27
R 1
J 0
(-9705 9153);
DISPLAY 1.212766 (-9705 9153);
PAINT GREEN (-9705 9153);
DISPLAY INVISIBLE (-9705 9153);
FORCEPROP 1 LAST TOLERANCE 1%
R 1
J 0
(-9855 9153);
DISPLAY 1.212766 (-9855 9153);
PAINT GREEN (-9855 9153);
DISPLAY INVISIBLE (-9855 9153);
FORCEPROP 1 LAST CLS_PN G155-14701-01
R 1
J 0
(-9800 9214);
DISPLAY 1.212766 (-9800 9214);
PAINT GREEN (-9800 9214);
DISPLAY INVISIBLE (-9800 9214);
FORCEADD RESISTOR..1
(-9300 9850);
FORCEPROP 1 LAST $LOCATION R128
J 2
(-9550 9850);
DISPLAY 1.212766 (-9550 9850);
PAINT GREEN (-9550 9850);
FORCEPROP 0 LAST CDS_LOCATION R128
J 0
(-9050 9950);
DISPLAY 1.021277 (-9050 9950);
DISPLAY INVISIBLE (-9050 9950);
FORCEPROP 0 LAST $SEC 1
J 0
(-9050 9950);
DISPLAY 0.680851 (-9050 9950);
PAINT MONO (-9050 9950);
DISPLAY INVISIBLE (-9050 9950);
FORCEPROP 0 LAST CDS_SEC 1
J 0
(-9050 9950);
DISPLAY 1.021277 (-9050 9950);
DISPLAY INVISIBLE (-9050 9950);
FORCEPROP 0 LASTPIN (-9400 9850) $PN 1
J 2
(-9410 9860);
DISPLAY 0.680851 (-9410 9860);
PAINT MONO (-9410 9860);
FORCEPROP 0 LASTPIN (-9150 9850) $PN 2
J 0
(-9140 9860);
DISPLAY 0.680851 (-9140 9860);
PAINT MONO (-9140 9860);
FORCEPROP 0 LAST PACKAGE 0402
J 0
(-9350 9900);
DISPLAY 1.021277 (-9350 9900);
FORCEPROP 1 LAST VALUE 0OHM
J 0
(-9050 9850);
DISPLAY 1.212766 (-9050 9850);
PAINT GREEN (-9050 9850);
FORCEPROP 1 LAST PATH I28
J 0
(-9497 9955);
DISPLAY 1.212766 (-9497 9955);
PAINT GREEN (-9497 9955);
DISPLAY INVISIBLE (-9497 9955);
FORCEPROP 1 LAST CLS_PN G155-100R0-J0
J 0
(-9436 10050);
DISPLAY 1.212766 (-9436 10050);
PAINT GREEN (-9436 10050);
DISPLAY INVISIBLE (-9436 10050);
FORCEPROP 1 LAST TOLERANCE -
J 0
(-9497 10105);
DISPLAY 1.212766 (-9497 10105);
PAINT GREEN (-9497 10105);
DISPLAY INVISIBLE (-9497 10105);
FORCEPROP 1 LAST CDS_LMAN_SYM_OUTLINE -50,50,100,-50
J 0
(-9300 9850);
DISPLAY 0.468085 (-9300 9850);
PAINT GREEN (-9300 9850);
DISPLAY INVISIBLE (-9300 9850);
FORCEPROP 2 LAST CDS_LIB passive
J 0
(-9300 9850);
DISPLAY INVISIBLE (-9300 9850);
FORCEADD RESISTOR..2
R 1
(-10250 8450);
FORCEPROP 1 LAST $LOCATION R455
J 0
(-10550 8500);
DISPLAY 1.212766 (-10550 8500);
PAINT GREEN (-10550 8500);
FORCEPROP 0 LAST CDS_LOCATION R455
R 1
J 0
(-10400 8650);
DISPLAY 1.021277 (-10400 8650);
DISPLAY INVISIBLE (-10400 8650);
FORCEPROP 0 LAST $SEC 1
R 1
J 0
(-10400 8650);
DISPLAY 0.680851 (-10400 8650);
PAINT MONO (-10400 8650);
DISPLAY INVISIBLE (-10400 8650);
FORCEPROP 0 LAST CDS_SEC 1
R 1
J 0
(-10400 8650);
DISPLAY 1.021277 (-10400 8650);
DISPLAY INVISIBLE (-10400 8650);
FORCEPROP 0 LASTPIN (-10350 8450) $PN 1
J 2
(-10360 8460);
DISPLAY 0.680851 (-10360 8460);
PAINT MONO (-10360 8460);
FORCEPROP 0 LASTPIN (-10100 8450) $PN 2
J 0
(-10090 8460);
DISPLAY 0.680851 (-10090 8460);
PAINT MONO (-10090 8460);
FORCEPROP 1 LAST VALUE 1MOHM
J 0
(-10050 8500);
DISPLAY 1.212766 (-10050 8500);
PAINT GREEN (-10050 8500);
FORCEPROP 0 LAST NO_ASSY TRUE
J 0
(-10400 8600);
DISPLAY 0.808511 (-10400 8600);
DISPLAY BOTH (-10400 8600);
FORCEPROP 0 LAST PACKAGE 0402
J 0
(-10300 8500);
DISPLAY 1.021277 (-10300 8500);
FORCEPROP 1 LAST TOLERANCE 1%
R 1
J 0
(-10505 8253);
DISPLAY 1.212766 (-10505 8253);
PAINT GREEN (-10505 8253);
DISPLAY INVISIBLE (-10505 8253);
FORCEPROP 1 LAST CLS_PN G155-11004-01
R 1
J 0
(-10450 8314);
DISPLAY 1.212766 (-10450 8314);
PAINT GREEN (-10450 8314);
DISPLAY INVISIBLE (-10450 8314);
FORCEPROP 1 LAST CDS_LMAN_SYM_OUTLINE -50,50,50,-100
R 1
J 0
(-10250 8450);
DISPLAY 0.468085 (-10250 8450);
PAINT GREEN (-10250 8450);
DISPLAY INVISIBLE (-10250 8450);
FORCEPROP 1 LAST PATH I287
R 1
J 0
(-10355 8253);
DISPLAY 1.212766 (-10355 8253);
PAINT GREEN (-10355 8253);
DISPLAY INVISIBLE (-10355 8253);
FORCEPROP 2 LAST CDS_LIB passive
R 1
J 0
(-10250 8450);
DISPLAY INVISIBLE (-10250 8450);
FORCEADD GND_SG..1
(-3050 7800);
FORCEPROP 3 LASTPIN (-3000 7850) SIG_NAME SG\g
J 0
(-2990 7860);
DISPLAY 0.659574 (-2990 7860);
PAINT MONO (-2990 7860);
DISPLAY INVISIBLE (-2990 7860);
FORCEPROP 1 LAST HDL_POWER SG
J 1
(-2995 7705);
DISPLAY 0.808511 (-2995 7705);
PAINT GREEN (-2995 7705);
FORCEPROP 2 LAST CDS_LIB cls
J 0
(-3050 7800);
DISPLAY INVISIBLE (-3050 7800);
FORCEPROP 1 LAST PATH I288
J 0
(-3015 7800);
DISPLAY 0.808511 (-3015 7800);
PAINT GREEN (-3015 7800);
DISPLAY INVISIBLE (-3015 7800);
FORCEPROP 1 LAST CDS_LMAN_SYM_OUTLINE 0,0,100,-50
J 0
(-3050 7800);
DISPLAY 0.468085 (-3050 7800);
PAINT GREEN (-3050 7800);
DISPLAY INVISIBLE (-3050 7800);
FORCEPROP 1 LAST BODY_TYPE PLUMBING
J 0
(-3035 7785);
DISPLAY 0.808511 (-3035 7785);
PAINT GREEN (-3035 7785);
DISPLAY INVISIBLE (-3035 7785);
FORCEADD OFFPAGE_OUT..1
(-5850 11050);
FORCEPROP 2 LAST $XR0 24J5< 
J 0
(-5795 11050);
DISPLAY 0.638298 (-5795 11050);
PAINT MONO (-5795 11050);
FORCEPROP 2 LAST CDS_LIB cls
J 0
(-5850 11050);
DISPLAY INVISIBLE (-5850 11050);
FORCEPROP 2 LAST PATH I297
J 0
(-5800 11150);
DISPLAY 1.021277 (-5800 11150);
DISPLAY INVISIBLE (-5800 11150);
FORCEPROP 1 LAST CDS_LMAN_SYM_OUTLINE -50,50,50,-50
J 0
(-5850 11050);
DISPLAY 0.468085 (-5850 11050);
PAINT GREEN (-5850 11050);
DISPLAY INVISIBLE (-5850 11050);
FORCEPROP 1 LAST BODY_TYPE COMMENT
J 0
(-5840 11185);
DISPLAY 0.808511 (-5840 11185);
PAINT GREEN (-5840 11185);
DISPLAY INVISIBLE (-5840 11185);
FORCEPROP 1 LAST OFFPAGE TRUE
J 0
(-5840 11105);
DISPLAY 0.808511 (-5840 11105);
PAINT GREEN (-5840 11105);
DISPLAY INVISIBLE (-5840 11105);
FORCEADD OFFPAGE_OUT..1
(-5850 10950);
FORCEPROP 2 LAST $XR0 24J6< 
J 0
(-5795 10950);
DISPLAY 0.638298 (-5795 10950);
PAINT MONO (-5795 10950);
FORCEPROP 2 LAST CDS_LIB cls
J 0
(-5850 10950);
DISPLAY INVISIBLE (-5850 10950);
FORCEPROP 1 LAST CDS_LMAN_SYM_OUTLINE -50,50,50,-50
J 0
(-5850 10950);
DISPLAY 0.468085 (-5850 10950);
PAINT GREEN (-5850 10950);
DISPLAY INVISIBLE (-5850 10950);
FORCEPROP 1 LAST BODY_TYPE COMMENT
J 0
(-5840 11085);
DISPLAY 0.808511 (-5840 11085);
PAINT GREEN (-5840 11085);
DISPLAY INVISIBLE (-5840 11085);
FORCEPROP 1 LAST OFFPAGE TRUE
J 0
(-5840 11005);
DISPLAY 0.808511 (-5840 11005);
PAINT GREEN (-5840 11005);
DISPLAY INVISIBLE (-5840 11005);
FORCEPROP 2 LAST PATH I298
J 0
(-5800 11050);
DISPLAY 1.021277 (-5800 11050);
DISPLAY INVISIBLE (-5800 11050);
FORCEADD OFFPAGE_OUT..1
(-5850 10850);
FORCEPROP 2 LAST $XR0 24K12< 
J 0
(-5795 10850);
DISPLAY 0.638298 (-5795 10850);
PAINT MONO (-5795 10850);
FORCEPROP 1 LAST OFFPAGE TRUE
J 0
(-5840 10905);
DISPLAY 0.808511 (-5840 10905);
PAINT GREEN (-5840 10905);
DISPLAY INVISIBLE (-5840 10905);
FORCEPROP 1 LAST BODY_TYPE COMMENT
J 0
(-5840 10985);
DISPLAY 0.808511 (-5840 10985);
PAINT GREEN (-5840 10985);
DISPLAY INVISIBLE (-5840 10985);
FORCEPROP 1 LAST CDS_LMAN_SYM_OUTLINE -50,50,50,-50
J 0
(-5850 10850);
DISPLAY 0.468085 (-5850 10850);
PAINT GREEN (-5850 10850);
DISPLAY INVISIBLE (-5850 10850);
FORCEPROP 2 LAST CDS_LIB cls
J 0
(-5850 10850);
DISPLAY INVISIBLE (-5850 10850);
FORCEPROP 2 LAST PATH I299
J 0
(-5800 10950);
DISPLAY 1.021277 (-5800 10950);
DISPLAY INVISIBLE (-5800 10950);
FORCEADD CL1001485A..1
R 7
(-11900 8900);
FORCEPROP 1 LAST $LOCATION U17
J 0
(-12050 8600);
DISPLAY 1.212766 (-12050 8600);
PAINT GREEN (-12050 8600);
FORCEPROP 0 LAST CDS_LOCATION U17
J 0
(-11350 9300);
DISPLAY 1.021277 (-11350 9300);
DISPLAY INVISIBLE (-11350 9300);
FORCEPROP 0 LAST $SEC 1
J 0
(-11350 9300);
DISPLAY 0.680851 (-11350 9300);
PAINT MONO (-11350 9300);
DISPLAY INVISIBLE (-11350 9300);
FORCEPROP 0 LAST CDS_SEC 1
J 0
(-11350 9300);
DISPLAY 1.021277 (-11350 9300);
DISPLAY INVISIBLE (-11350 9300);
FORCEPROP 0 LASTPIN (-12000 8800) $PN 1
R 1
J 2
(-12010 8790);
DISPLAY 0.680851 (-12010 8790);
PAINT MONO (-12010 8790);
FORCEPROP 0 LASTPIN (-12200 8800) $PN 2
R 1
J 2
(-12210 8790);
DISPLAY 0.680851 (-12210 8790);
PAINT MONO (-12210 8790);
FORCEPROP 0 LASTPIN (-12400 8800) $PN 3
R 1
J 2
(-12410 8790);
DISPLAY 0.680851 (-12410 8790);
PAINT MONO (-12410 8790);
FORCEPROP 0 LASTPIN (-12400 9450) $PN 4
R 1
J 0
(-12410 9460);
DISPLAY 0.680851 (-12410 9460);
PAINT MONO (-12410 9460);
FORCEPROP 0 LASTPIN (-12200 9450) $PN 5
R 1
J 0
(-12210 9460);
DISPLAY 0.680851 (-12210 9460);
PAINT MONO (-12210 9460);
FORCEPROP 0 LASTPIN (-12000 9450) $PN 6
R 1
J 0
(-12010 9460);
DISPLAY 0.680851 (-12010 9460);
PAINT MONO (-12010 9460);
FORCEPROP 1 LAST CLS_PN G122-00019-01
J 0
(-12050 8500);
DISPLAY 1.212766 (-12050 8500);
PAINT GREEN (-12050 8500);
FORCEPROP 0 LAST PART_NUMBER SRV05-4ATCT
J 0
(-12050 8550);
DISPLAY 1.021277 (-12050 8550);
FORCEPROP 1 LAST PATH I3
R 1
J 0
(-11841 9440);
DISPLAY 1.212766 (-11841 9440);
PAINT GREEN (-11841 9440);
DISPLAY INVISIBLE (-11841 9440);
FORCEPROP 1 LAST CDS_LMAN_SYM_OUTLINE 0,0,450,-600
R 1
J 0
(-11878 8878);
DISPLAY 0.468085 (-11878 8878);
PAINT GREEN (-11878 8878);
DISPLAY INVISIBLE (-11878 8878);
FORCEPROP 2 LAST CDS_LIB other
R 1
J 0
(-11853 8853);
DISPLAY INVISIBLE (-11853 8853);
FORCEADD RESISTOR..1
R 2
(-11950 6850);
FORCEPROP 1 LAST $LOCATION R454
J 0
(-12350 6850);
DISPLAY 1.212766 (-12350 6850);
PAINT GREEN (-12350 6850);
FORCEPROP 0 LAST CDS_LOCATION R454
J 0
(-11400 6950);
DISPLAY 1.021277 (-11400 6950);
DISPLAY INVISIBLE (-11400 6950);
FORCEPROP 0 LAST $SEC 1
J 0
(-11400 6950);
DISPLAY 0.680851 (-11400 6950);
PAINT MONO (-11400 6950);
DISPLAY INVISIBLE (-11400 6950);
FORCEPROP 0 LAST CDS_SEC 1
J 0
(-11400 6950);
DISPLAY 1.021277 (-11400 6950);
DISPLAY INVISIBLE (-11400 6950);
FORCEPROP 0 LASTPIN (-11850 6850) $PN 1
J 0
(-11840 6860);
DISPLAY 0.680851 (-11840 6860);
PAINT MONO (-11840 6860);
FORCEPROP 0 LASTPIN (-12100 6850) $PN 2
J 2
(-12110 6860);
DISPLAY 0.680851 (-12110 6860);
PAINT MONO (-12110 6860);
FORCEPROP 0 LAST PACKAGE 0402
J 2
(-11850 6750);
DISPLAY 1.021277 (-11850 6750);
FORCEPROP 1 LAST VALUE 2.2KOHM
J 2
(-11400 6850);
DISPLAY 1.212766 (-11400 6850);
PAINT GREEN (-11400 6850);
FORCEPROP 1 LAST TOLERANCE 1%
J 2
(-11753 7105);
DISPLAY 1.212766 (-11753 7105);
PAINT GREEN (-11753 7105);
DISPLAY INVISIBLE (-11753 7105);
FORCEPROP 1 LAST CDS_LMAN_SYM_OUTLINE -50,50,100,-50
J 2
(-11950 6850);
DISPLAY 0.468085 (-11950 6850);
PAINT GREEN (-11950 6850);
DISPLAY INVISIBLE (-11950 6850);
FORCEPROP 1 LAST PATH I310
J 2
(-11753 6955);
DISPLAY 1.212766 (-11753 6955);
PAINT GREEN (-11753 6955);
DISPLAY INVISIBLE (-11753 6955);
FORCEPROP 2 LAST CDS_LIB passive
R 3
J 0
(-11950 6850);
DISPLAY INVISIBLE (-11950 6850);
FORCEPROP 1 LAST CLS_PN G155-12201-01
J 2
(-11814 7050);
DISPLAY 1.212766 (-11814 7050);
PAINT GREEN (-11814 7050);
DISPLAY INVISIBLE (-11814 7050);
FORCEADD TP_PIONT..1
(-6250 10750);
FORCEPROP 1 LAST $LOCATION TP5
J 0
(-6150 10750);
DISPLAY 0.808511 (-6150 10750);
PAINT GREEN (-6150 10750);
FORCEPROP 0 LAST CDS_LOCATION TP5
J 0
(-6150 10800);
DISPLAY 1.021277 (-6150 10800);
DISPLAY INVISIBLE (-6150 10800);
FORCEPROP 0 LAST $SEC 1
J 0
(-6150 10800);
DISPLAY 0.680851 (-6150 10800);
PAINT MONO (-6150 10800);
DISPLAY INVISIBLE (-6150 10800);
FORCEPROP 0 LAST CDS_SEC 1
J 0
(-6150 10800);
DISPLAY 1.021277 (-6150 10800);
DISPLAY INVISIBLE (-6150 10800);
FORCEPROP 0 LASTPIN (-6350 10750) $PN 1
J 2
(-6360 10760);
DISPLAY 0.680851 (-6360 10760);
PAINT MONO (-6360 10760);
FORCEPROP 1 LAST PATH I311
J 0
(-6170 10863);
DISPLAY 0.808511 (-6170 10863);
PAINT GREEN (-6170 10863);
DISPLAY INVISIBLE (-6170 10863);
FORCEPROP 1 LAST BOM_IGNORE TRUE
J 0
(-6374 10850);
DISPLAY 0.000000 (-6374 10850);
PAINT GREEN (-6374 10850);
DISPLAY INVISIBLE (-6374 10850);
FORCEPROP 1 LAST JEDEC_TYPE TP010CT020B030_PTH
J 0
(-6374 10850);
DISPLAY 0.000000 (-6374 10850);
PAINT GREEN (-6374 10850);
DISPLAY INVISIBLE (-6374 10850);
FORCEPROP 1 LAST CDS_LMAN_SYM_OUTLINE -50,50,50,-50
J 0
(-6250 10750);
DISPLAY 0.468085 (-6250 10750);
PAINT GREEN (-6250 10750);
DISPLAY INVISIBLE (-6250 10750);
FORCEPROP 2 LAST CDS_LIB cls
J 0
(-6250 10750);
DISPLAY INVISIBLE (-6250 10750);
FORCEADD TP_PIONT..1
(-6250 10250);
FORCEPROP 1 LAST $LOCATION TP6
J 0
(-6150 10250);
DISPLAY 0.808511 (-6150 10250);
PAINT GREEN (-6150 10250);
FORCEPROP 0 LAST CDS_LOCATION TP6
J 0
(-6150 10300);
DISPLAY 1.021277 (-6150 10300);
DISPLAY INVISIBLE (-6150 10300);
FORCEPROP 0 LAST $SEC 1
J 0
(-6150 10300);
DISPLAY 0.680851 (-6150 10300);
PAINT MONO (-6150 10300);
DISPLAY INVISIBLE (-6150 10300);
FORCEPROP 0 LAST CDS_SEC 1
J 0
(-6150 10300);
DISPLAY 1.021277 (-6150 10300);
DISPLAY INVISIBLE (-6150 10300);
FORCEPROP 0 LASTPIN (-6350 10250) $PN 1
J 2
(-6360 10260);
DISPLAY 0.680851 (-6360 10260);
PAINT MONO (-6360 10260);
FORCEPROP 1 LAST PATH I312
J 0
(-6170 10363);
DISPLAY 0.808511 (-6170 10363);
PAINT GREEN (-6170 10363);
DISPLAY INVISIBLE (-6170 10363);
FORCEPROP 1 LAST BOM_IGNORE TRUE
J 0
(-6374 10350);
DISPLAY 0.000000 (-6374 10350);
PAINT GREEN (-6374 10350);
DISPLAY INVISIBLE (-6374 10350);
FORCEPROP 1 LAST JEDEC_TYPE TP010CT020B030_PTH
J 0
(-6374 10350);
DISPLAY 0.000000 (-6374 10350);
PAINT GREEN (-6374 10350);
DISPLAY INVISIBLE (-6374 10350);
FORCEPROP 1 LAST CDS_LMAN_SYM_OUTLINE -50,50,50,-50
J 0
(-6250 10250);
DISPLAY 0.468085 (-6250 10250);
PAINT GREEN (-6250 10250);
DISPLAY INVISIBLE (-6250 10250);
FORCEPROP 2 LAST CDS_LIB cls
J 0
(-6250 10250);
DISPLAY INVISIBLE (-6250 10250);
FORCEADD TP_PIONT..1
(-6250 10150);
FORCEPROP 1 LAST $LOCATION TP7
J 0
(-6150 10150);
DISPLAY 0.808511 (-6150 10150);
PAINT GREEN (-6150 10150);
FORCEPROP 0 LAST CDS_LOCATION TP7
J 0
(-6150 10200);
DISPLAY 1.021277 (-6150 10200);
DISPLAY INVISIBLE (-6150 10200);
FORCEPROP 0 LAST $SEC 1
J 0
(-6150 10200);
DISPLAY 0.680851 (-6150 10200);
PAINT MONO (-6150 10200);
DISPLAY INVISIBLE (-6150 10200);
FORCEPROP 0 LAST CDS_SEC 1
J 0
(-6150 10200);
DISPLAY 1.021277 (-6150 10200);
DISPLAY INVISIBLE (-6150 10200);
FORCEPROP 0 LASTPIN (-6350 10150) $PN 1
J 2
(-6360 10160);
DISPLAY 0.680851 (-6360 10160);
PAINT MONO (-6360 10160);
FORCEPROP 1 LAST PATH I313
J 0
(-6170 10263);
DISPLAY 0.808511 (-6170 10263);
PAINT GREEN (-6170 10263);
DISPLAY INVISIBLE (-6170 10263);
FORCEPROP 1 LAST BOM_IGNORE TRUE
J 0
(-6374 10250);
DISPLAY 0.000000 (-6374 10250);
PAINT GREEN (-6374 10250);
DISPLAY INVISIBLE (-6374 10250);
FORCEPROP 1 LAST JEDEC_TYPE TP010CT020B030_PTH
J 0
(-6374 10250);
DISPLAY 0.000000 (-6374 10250);
PAINT GREEN (-6374 10250);
DISPLAY INVISIBLE (-6374 10250);
FORCEPROP 1 LAST CDS_LMAN_SYM_OUTLINE -50,50,50,-50
J 0
(-6250 10150);
DISPLAY 0.468085 (-6250 10150);
PAINT GREEN (-6250 10150);
DISPLAY INVISIBLE (-6250 10150);
FORCEPROP 2 LAST CDS_LIB cls
J 0
(-6250 10150);
DISPLAY INVISIBLE (-6250 10150);
FORCEADD TP_PIONT..1
(-6250 9950);
FORCEPROP 1 LAST $LOCATION TP9
J 0
(-6150 9950);
DISPLAY 0.808511 (-6150 9950);
PAINT GREEN (-6150 9950);
FORCEPROP 0 LAST CDS_LOCATION TP9
J 0
(-6150 10000);
DISPLAY 1.021277 (-6150 10000);
DISPLAY INVISIBLE (-6150 10000);
FORCEPROP 0 LAST $SEC 1
J 0
(-6150 10000);
DISPLAY 0.680851 (-6150 10000);
PAINT MONO (-6150 10000);
DISPLAY INVISIBLE (-6150 10000);
FORCEPROP 0 LAST CDS_SEC 1
J 0
(-6150 10000);
DISPLAY 1.021277 (-6150 10000);
DISPLAY INVISIBLE (-6150 10000);
FORCEPROP 0 LASTPIN (-6350 9950) $PN 1
J 2
(-6360 9960);
DISPLAY 0.680851 (-6360 9960);
PAINT MONO (-6360 9960);
FORCEPROP 1 LAST PATH I314
J 0
(-6170 10063);
DISPLAY 0.808511 (-6170 10063);
PAINT GREEN (-6170 10063);
DISPLAY INVISIBLE (-6170 10063);
FORCEPROP 1 LAST BOM_IGNORE TRUE
J 0
(-6374 10050);
DISPLAY 0.000000 (-6374 10050);
PAINT GREEN (-6374 10050);
DISPLAY INVISIBLE (-6374 10050);
FORCEPROP 1 LAST JEDEC_TYPE TP010CT020B030_PTH
J 0
(-6374 10050);
DISPLAY 0.000000 (-6374 10050);
PAINT GREEN (-6374 10050);
DISPLAY INVISIBLE (-6374 10050);
FORCEPROP 1 LAST CDS_LMAN_SYM_OUTLINE -50,50,50,-50
J 0
(-6250 9950);
DISPLAY 0.468085 (-6250 9950);
PAINT GREEN (-6250 9950);
DISPLAY INVISIBLE (-6250 9950);
FORCEPROP 2 LAST CDS_LIB cls
J 0
(-6250 9950);
DISPLAY INVISIBLE (-6250 9950);
FORCEADD TP_PIONT..1
(-6250 10050);
FORCEPROP 1 LAST $LOCATION TP8
J 0
(-6150 10050);
DISPLAY 0.808511 (-6150 10050);
PAINT GREEN (-6150 10050);
FORCEPROP 0 LAST CDS_LOCATION TP8
J 0
(-6150 10100);
DISPLAY 1.021277 (-6150 10100);
DISPLAY INVISIBLE (-6150 10100);
FORCEPROP 0 LAST $SEC 1
J 0
(-6150 10100);
DISPLAY 0.680851 (-6150 10100);
PAINT MONO (-6150 10100);
DISPLAY INVISIBLE (-6150 10100);
FORCEPROP 0 LAST CDS_SEC 1
J 0
(-6150 10100);
DISPLAY 1.021277 (-6150 10100);
DISPLAY INVISIBLE (-6150 10100);
FORCEPROP 0 LASTPIN (-6350 10050) $PN 1
J 2
(-6360 10060);
DISPLAY 0.680851 (-6360 10060);
PAINT MONO (-6360 10060);
FORCEPROP 2 LAST CDS_LIB cls
J 0
(-6250 10050);
DISPLAY INVISIBLE (-6250 10050);
FORCEPROP 1 LAST CDS_LMAN_SYM_OUTLINE -50,50,50,-50
J 0
(-6250 10050);
DISPLAY 0.468085 (-6250 10050);
PAINT GREEN (-6250 10050);
DISPLAY INVISIBLE (-6250 10050);
FORCEPROP 1 LAST JEDEC_TYPE TP010CT020B030_PTH
J 0
(-6374 10150);
DISPLAY 0.000000 (-6374 10150);
PAINT GREEN (-6374 10150);
DISPLAY INVISIBLE (-6374 10150);
FORCEPROP 1 LAST BOM_IGNORE TRUE
J 0
(-6374 10150);
DISPLAY 0.000000 (-6374 10150);
PAINT GREEN (-6374 10150);
DISPLAY INVISIBLE (-6374 10150);
FORCEPROP 1 LAST PATH I315
J 0
(-6170 10163);
DISPLAY 0.808511 (-6170 10163);
PAINT GREEN (-6170 10163);
DISPLAY INVISIBLE (-6170 10163);
FORCEADD TP_PIONT..1
(-6250 9850);
FORCEPROP 1 LAST $LOCATION TP10
J 0
(-6150 9850);
DISPLAY 0.808511 (-6150 9850);
PAINT GREEN (-6150 9850);
FORCEPROP 0 LAST CDS_LOCATION TP10
J 0
(-6150 9900);
DISPLAY 1.021277 (-6150 9900);
DISPLAY INVISIBLE (-6150 9900);
FORCEPROP 0 LAST $SEC 1
J 0
(-6150 9900);
DISPLAY 0.680851 (-6150 9900);
PAINT MONO (-6150 9900);
DISPLAY INVISIBLE (-6150 9900);
FORCEPROP 0 LAST CDS_SEC 1
J 0
(-6150 9900);
DISPLAY 1.021277 (-6150 9900);
DISPLAY INVISIBLE (-6150 9900);
FORCEPROP 0 LASTPIN (-6350 9850) $PN 1
J 2
(-6360 9860);
DISPLAY 0.680851 (-6360 9860);
PAINT MONO (-6360 9860);
FORCEPROP 2 LAST CDS_LIB cls
J 0
(-6250 9850);
DISPLAY INVISIBLE (-6250 9850);
FORCEPROP 1 LAST CDS_LMAN_SYM_OUTLINE -50,50,50,-50
J 0
(-6250 9850);
DISPLAY 0.468085 (-6250 9850);
PAINT GREEN (-6250 9850);
DISPLAY INVISIBLE (-6250 9850);
FORCEPROP 1 LAST JEDEC_TYPE TP010CT020B030_PTH
J 0
(-6374 9950);
DISPLAY 0.000000 (-6374 9950);
PAINT GREEN (-6374 9950);
DISPLAY INVISIBLE (-6374 9950);
FORCEPROP 1 LAST BOM_IGNORE TRUE
J 0
(-6374 9950);
DISPLAY 0.000000 (-6374 9950);
PAINT GREEN (-6374 9950);
DISPLAY INVISIBLE (-6374 9950);
FORCEPROP 1 LAST PATH I316
J 0
(-6170 9963);
DISPLAY 0.808511 (-6170 9963);
PAINT GREEN (-6170 9963);
DISPLAY INVISIBLE (-6170 9963);
FORCEADD OFFPAGE_IN..2
R 2
(-10650 9500);
FORCEPROP 2 LAST $XR0 33F10> 
J 0
(-10864 9500);
DISPLAY 0.638298 (-10864 9500);
PAINT MONO (-10864 9500);
FORCEPROP 1 LAST OFFPAGE TRUE
J 2
(-10660 9555);
DISPLAY 0.808511 (-10660 9555);
PAINT GREEN (-10660 9555);
DISPLAY INVISIBLE (-10660 9555);
FORCEPROP 1 LAST BODY_TYPE COMMENT
J 2
(-10660 9635);
DISPLAY 0.808511 (-10660 9635);
PAINT GREEN (-10660 9635);
DISPLAY INVISIBLE (-10660 9635);
FORCEPROP 1 LAST CDS_LMAN_SYM_OUTLINE -50,50,50,-50
J 2
(-10650 9500);
DISPLAY 0.468085 (-10650 9500);
PAINT GREEN (-10650 9500);
DISPLAY INVISIBLE (-10650 9500);
FORCEPROP 2 LAST PATH I350
J 0
(-10600 9600);
DISPLAY 1.021277 (-10600 9600);
DISPLAY INVISIBLE (-10600 9600);
FORCEPROP 2 LAST CDS_LIB cls
J 0
(-10650 9500);
DISPLAY INVISIBLE (-10650 9500);
FORCEADD VCC..1
(-11500 12000);
FORCEPROP 3 LASTPIN (-11450 11950) SIG_NAME XP3R3V_FT4232\g
J 0
(-11440 11960);
DISPLAY 0.659574 (-11440 11960);
PAINT MONO (-11440 11960);
DISPLAY INVISIBLE (-11440 11960);
FORCEPROP 1 LAST HDL_POWER XP3R3V_FT4232
J 1
(-11445 12055);
DISPLAY 1.021277 (-11445 12055);
PAINT GREEN (-11445 12055);
FORCEPROP 0 LAST VOLTAGE 3.3V
J 0
(-11750 12150);
DISPLAY 1.021277 (-11750 12150);
DISPLAY BOTH (-11750 12150);
FORCEPROP 1 LAST BODY_TYPE PLUMBING
J 0
(-11545 11957);
DISPLAY 0.340426 (-11545 11957);
PAINT GREEN (-11545 11957);
DISPLAY INVISIBLE (-11545 11957);
FORCEPROP 1 LAST CDS_LMAN_SYM_OUTLINE -250,250,250,-250
J 0
(-11500 12000);
DISPLAY 0.468085 (-11500 12000);
PAINT GREEN (-11500 12000);
DISPLAY INVISIBLE (-11500 12000);
FORCEPROP 1 LAST PATH I359
J 0
(-11465 12090);
DISPLAY 0.808511 (-11465 12090);
PAINT GREEN (-11465 12090);
DISPLAY INVISIBLE (-11465 12090);
FORCEPROP 2 LAST CDS_LIB cls
J 0
(-11500 12000);
DISPLAY INVISIBLE (-11500 12000);
FORCEADD VCC..1
(-14200 8200);
FORCEPROP 3 LASTPIN (-14150 8150) SIG_NAME XP3R3V_FT4232\g
J 0
(-14140 8160);
DISPLAY 0.659574 (-14140 8160);
PAINT MONO (-14140 8160);
DISPLAY INVISIBLE (-14140 8160);
FORCEPROP 1 LAST HDL_POWER XP3R3V_FT4232
J 1
(-14145 8255);
DISPLAY 1.021277 (-14145 8255);
PAINT GREEN (-14145 8255);
FORCEPROP 0 LAST VOLTAGE 3.3V
J 0
(-14450 8350);
DISPLAY 1.021277 (-14450 8350);
DISPLAY BOTH (-14450 8350);
FORCEPROP 1 LAST BODY_TYPE PLUMBING
J 0
(-14245 8157);
DISPLAY 0.340426 (-14245 8157);
PAINT GREEN (-14245 8157);
DISPLAY INVISIBLE (-14245 8157);
FORCEPROP 1 LAST CDS_LMAN_SYM_OUTLINE -250,250,250,-250
J 0
(-14200 8200);
DISPLAY 0.468085 (-14200 8200);
PAINT GREEN (-14200 8200);
DISPLAY INVISIBLE (-14200 8200);
FORCEPROP 1 LAST PATH I360
J 0
(-14165 8290);
DISPLAY 0.808511 (-14165 8290);
PAINT GREEN (-14165 8290);
DISPLAY INVISIBLE (-14165 8290);
FORCEPROP 2 LAST CDS_LIB cls
J 0
(-14200 8200);
DISPLAY INVISIBLE (-14200 8200);
FORCEADD VCC..1
(-3200 9150);
FORCEPROP 3 LASTPIN (-3150 9100) SIG_NAME XP3R3V_FT4232\g
J 0
(-3140 9110);
DISPLAY 0.659574 (-3140 9110);
PAINT MONO (-3140 9110);
DISPLAY INVISIBLE (-3140 9110);
FORCEPROP 0 LAST VOLTAGE 3.3V
J 0
(-3450 9300);
DISPLAY 1.021277 (-3450 9300);
DISPLAY BOTH (-3450 9300);
FORCEPROP 1 LAST HDL_POWER XP3R3V_FT4232
J 1
(-3145 9205);
DISPLAY 1.021277 (-3145 9205);
PAINT GREEN (-3145 9205);
FORCEPROP 1 LAST BODY_TYPE PLUMBING
J 0
(-3245 9107);
DISPLAY 0.340426 (-3245 9107);
PAINT GREEN (-3245 9107);
DISPLAY INVISIBLE (-3245 9107);
FORCEPROP 1 LAST CDS_LMAN_SYM_OUTLINE -250,250,250,-250
J 0
(-3200 9150);
DISPLAY 0.468085 (-3200 9150);
PAINT GREEN (-3200 9150);
DISPLAY INVISIBLE (-3200 9150);
FORCEPROP 1 LAST PATH I362
J 0
(-3165 9240);
DISPLAY 0.808511 (-3165 9240);
PAINT GREEN (-3165 9240);
DISPLAY INVISIBLE (-3165 9240);
FORCEPROP 2 LAST CDS_LIB cls
J 0
(-3200 9150);
DISPLAY INVISIBLE (-3200 9150);
FORCEADD VCC..1
(-3300 10100);
FORCEPROP 3 LASTPIN (-3250 10050) SIG_NAME XP3R3V_FT4232\g
J 0
(-3240 10060);
DISPLAY 0.659574 (-3240 10060);
PAINT MONO (-3240 10060);
DISPLAY INVISIBLE (-3240 10060);
FORCEPROP 1 LAST HDL_POWER XP3R3V_FT4232
J 1
(-3245 10155);
DISPLAY 1.021277 (-3245 10155);
PAINT GREEN (-3245 10155);
FORCEPROP 0 LAST VOLTAGE 3.3V
J 0
(-3550 10250);
DISPLAY 1.021277 (-3550 10250);
DISPLAY BOTH (-3550 10250);
FORCEPROP 2 LAST CDS_LIB cls
J 0
(-3300 10100);
DISPLAY INVISIBLE (-3300 10100);
FORCEPROP 1 LAST PATH I363
J 0
(-3265 10190);
DISPLAY 0.808511 (-3265 10190);
PAINT GREEN (-3265 10190);
DISPLAY INVISIBLE (-3265 10190);
FORCEPROP 1 LAST CDS_LMAN_SYM_OUTLINE -250,250,250,-250
J 0
(-3300 10100);
DISPLAY 0.468085 (-3300 10100);
PAINT GREEN (-3300 10100);
DISPLAY INVISIBLE (-3300 10100);
FORCEPROP 1 LAST BODY_TYPE PLUMBING
J 0
(-3345 10057);
DISPLAY 0.340426 (-3345 10057);
PAINT GREEN (-3345 10057);
DISPLAY INVISIBLE (-3345 10057);
FORCEADD VCC..1
(-4550 11750);
FORCEPROP 3 LASTPIN (-4500 11700) SIG_NAME XP3R3V_FT4232\g
J 0
(-4490 11710);
DISPLAY 0.659574 (-4490 11710);
PAINT MONO (-4490 11710);
DISPLAY INVISIBLE (-4490 11710);
FORCEPROP 1 LAST HDL_POWER XP3R3V_FT4232
J 1
(-4495 11805);
DISPLAY 1.021277 (-4495 11805);
PAINT GREEN (-4495 11805);
FORCEPROP 0 LAST VOLTAGE 3.3V
J 0
(-4800 11900);
DISPLAY 1.021277 (-4800 11900);
DISPLAY BOTH (-4800 11900);
FORCEPROP 2 LAST CDS_LIB cls
J 0
(-4550 11750);
DISPLAY INVISIBLE (-4550 11750);
FORCEPROP 1 LAST PATH I364
J 0
(-4515 11840);
DISPLAY 0.808511 (-4515 11840);
PAINT GREEN (-4515 11840);
DISPLAY INVISIBLE (-4515 11840);
FORCEPROP 1 LAST CDS_LMAN_SYM_OUTLINE -250,250,250,-250
J 0
(-4550 11750);
DISPLAY 0.468085 (-4550 11750);
PAINT GREEN (-4550 11750);
DISPLAY INVISIBLE (-4550 11750);
FORCEPROP 1 LAST BODY_TYPE PLUMBING
J 0
(-4595 11707);
DISPLAY 0.340426 (-4595 11707);
PAINT GREEN (-4595 11707);
DISPLAY INVISIBLE (-4595 11707);
FORCEADD VCC..1
(-8250 11950);
FORCEPROP 3 LASTPIN (-8200 11900) SIG_NAME XP3R3V_FT4232\g
J 0
(-8190 11910);
DISPLAY 0.659574 (-8190 11910);
PAINT MONO (-8190 11910);
DISPLAY INVISIBLE (-8190 11910);
FORCEPROP 0 LAST VOLTAGE 3.3V
J 0
(-8500 12100);
DISPLAY 1.021277 (-8500 12100);
DISPLAY BOTH (-8500 12100);
FORCEPROP 1 LAST HDL_POWER XP3R3V_FT4232
J 1
(-8195 12005);
DISPLAY 1.021277 (-8195 12005);
PAINT GREEN (-8195 12005);
FORCEPROP 1 LAST BODY_TYPE PLUMBING
J 0
(-8295 11907);
DISPLAY 0.340426 (-8295 11907);
PAINT GREEN (-8295 11907);
DISPLAY INVISIBLE (-8295 11907);
FORCEPROP 1 LAST CDS_LMAN_SYM_OUTLINE -250,250,250,-250
J 0
(-8250 11950);
DISPLAY 0.468085 (-8250 11950);
PAINT GREEN (-8250 11950);
DISPLAY INVISIBLE (-8250 11950);
FORCEPROP 1 LAST PATH I365
J 0
(-8215 12040);
DISPLAY 0.808511 (-8215 12040);
PAINT GREEN (-8215 12040);
DISPLAY INVISIBLE (-8215 12040);
FORCEPROP 2 LAST CDS_LIB cls
J 0
(-8250 11950);
DISPLAY INVISIBLE (-8250 11950);
FORCEADD RESISTOR..1
(-9600 9500);
FORCEPROP 1 LAST $LOCATION R456
J 2
(-9750 9500);
DISPLAY 1.212766 (-9750 9500);
PAINT GREEN (-9750 9500);
FORCEPROP 0 LAST CDS_LOCATION R456
J 0
(-9350 9650);
DISPLAY 1.021277 (-9350 9650);
DISPLAY INVISIBLE (-9350 9650);
FORCEPROP 0 LAST $SEC 1
J 0
(-9350 9650);
DISPLAY 0.680851 (-9350 9650);
PAINT MONO (-9350 9650);
DISPLAY INVISIBLE (-9350 9650);
FORCEPROP 0 LAST CDS_SEC 1
J 0
(-9350 9650);
DISPLAY 1.021277 (-9350 9650);
DISPLAY INVISIBLE (-9350 9650);
FORCEPROP 0 LASTPIN (-9700 9500) $PN 1
J 2
(-9710 9510);
DISPLAY 0.680851 (-9710 9510);
PAINT MONO (-9710 9510);
FORCEPROP 0 LASTPIN (-9450 9500) $PN 2
J 0
(-9440 9510);
DISPLAY 0.680851 (-9440 9510);
PAINT MONO (-9440 9510);
FORCEPROP 1 LAST VALUE 100OHM
J 0
(-9350 9550);
DISPLAY 1.212766 (-9350 9550);
PAINT GREEN (-9350 9550);
FORCEPROP 0 LAST PACKAGE 0402
J 0
(-9650 9550);
DISPLAY 0.808511 (-9650 9550);
FORCEPROP 1 LAST PATH I368
J 0
(-9797 9605);
DISPLAY 1.212766 (-9797 9605);
PAINT GREEN (-9797 9605);
DISPLAY INVISIBLE (-9797 9605);
FORCEPROP 2 LAST CDS_LIB passive
J 0
(-9600 9500);
DISPLAY INVISIBLE (-9600 9500);
FORCEPROP 1 LAST CDS_LMAN_SYM_OUTLINE -50,50,100,-50
J 0
(-9600 9500);
DISPLAY 0.468085 (-9600 9500);
PAINT GREEN (-9600 9500);
DISPLAY INVISIBLE (-9600 9500);
FORCEPROP 1 LAST CLS_PN G155-11000-01
J 0
(-9736 9700);
DISPLAY 1.212766 (-9736 9700);
PAINT GREEN (-9736 9700);
DISPLAY INVISIBLE (-9736 9700);
FORCEPROP 1 LAST TOLERANCE 1%
J 0
(-9797 9755);
DISPLAY 1.212766 (-9797 9755);
PAINT GREEN (-9797 9755);
DISPLAY INVISIBLE (-9797 9755);
FORCEADD OFFPAGE_OUT..1
R 2
(-10650 9250);
FORCEPROP 2 LAST $XR0 25C6<> 
J 0
(-10864 9250);
DISPLAY 0.638298 (-10864 9250);
PAINT MONO (-10864 9250);
FORCEPROP 2 LAST $XR1 24K1< 
J 0
(-11044 9250);
DISPLAY 0.638298 (-11044 9250);
PAINT MONO (-11044 9250);
FORCEPROP 1 LAST BODY_TYPE COMMENT
J 2
(-10660 9385);
DISPLAY 0.808511 (-10660 9385);
PAINT GREEN (-10660 9385);
DISPLAY INVISIBLE (-10660 9385);
FORCEPROP 1 LAST OFFPAGE TRUE
J 2
(-10660 9305);
DISPLAY 0.808511 (-10660 9305);
PAINT GREEN (-10660 9305);
DISPLAY INVISIBLE (-10660 9305);
FORCEPROP 1 LAST CDS_LMAN_SYM_OUTLINE -50,50,50,-50
J 2
(-10650 9250);
DISPLAY 0.468085 (-10650 9250);
PAINT GREEN (-10650 9250);
DISPLAY INVISIBLE (-10650 9250);
FORCEPROP 2 LAST PATH I370
J 0
(-10600 9350);
DISPLAY 1.021277 (-10600 9350);
DISPLAY INVISIBLE (-10600 9350);
FORCEPROP 2 LAST CDS_LIB cls
J 0
(-10650 9250);
DISPLAY INVISIBLE (-10650 9250);
FORCEADD CAPACITOR..2
R 2
(-9000 10800);
FORCEPROP 1 LAST $LOCATION C101
J 2
(-8700 10750);
DISPLAY 1.212766 (-8700 10750);
PAINT GREEN (-8700 10750);
FORCEPROP 0 LAST CDS_LOCATION C101
J 0
(-8900 11000);
DISPLAY 1.021277 (-8900 11000);
DISPLAY INVISIBLE (-8900 11000);
FORCEPROP 0 LAST $SEC 1
J 0
(-8900 11000);
DISPLAY 0.680851 (-8900 11000);
PAINT MONO (-8900 11000);
DISPLAY INVISIBLE (-8900 11000);
FORCEPROP 0 LAST CDS_SEC 1
J 0
(-8900 11000);
DISPLAY 1.021277 (-8900 11000);
DISPLAY INVISIBLE (-8900 11000);
FORCEPROP 0 LASTPIN (-9000 10900) $PN 1
R 1
J 0
(-9010 10910);
DISPLAY 0.680851 (-9010 10910);
PAINT MONO (-9010 10910);
FORCEPROP 0 LASTPIN (-9000 10650) $PN 2
R 1
J 2
(-9010 10640);
DISPLAY 0.680851 (-9010 10640);
PAINT MONO (-9010 10640);
FORCEPROP 1 LAST VALUE 0.1UF
J 2
(-8650 10850);
DISPLAY 1.212766 (-8650 10850);
PAINT GREEN (-8650 10850);
FORCEPROP 0 LAST VOLTAGE 25V
J 0
(-8900 10650);
DISPLAY 1.021277 (-8900 10650);
FORCEPROP 0 LAST PACKAGE 0402
J 0
(-8900 10950);
DISPLAY 1.021277 (-8900 10950);
FORCEPROP 2 LAST CDS_LIB passive
J 0
(-9000 10800);
DISPLAY INVISIBLE (-9000 10800);
FORCEPROP 1 LAST PATH I373
J 2
(-8900 10850);
DISPLAY 1.212766 (-8900 10850);
PAINT GREEN (-8900 10850);
DISPLAY INVISIBLE (-8900 10850);
FORCEPROP 1 LAST CDS_LMAN_SYM_OUTLINE -50,0,50,-50
J 2
(-9000 10800);
DISPLAY 0.468085 (-9000 10800);
PAINT GREEN (-9000 10800);
DISPLAY INVISIBLE (-9000 10800);
FORCEPROP 1 LAST CLS_PN G105-0B104-EK
J 2
(-8900 10850);
DISPLAY 1.212766 (-8900 10850);
PAINT GREEN (-8900 10850);
DISPLAY INVISIBLE (-8900 10850);
FORCEPROP 1 LAST TOLERANCE 10%
J 2
(-8850 10900);
DISPLAY 1.212766 (-8850 10900);
PAINT GREEN (-8850 10900);
DISPLAY INVISIBLE (-8850 10900);
FORCEADD CAPACITOR..2
R 2
(-9000 11600);
FORCEPROP 1 LAST $LOCATION C100
J 2
(-8700 11550);
DISPLAY 1.212766 (-8700 11550);
PAINT GREEN (-8700 11550);
FORCEPROP 0 LAST CDS_LOCATION C100
J 0
(-8900 11800);
DISPLAY 1.021277 (-8900 11800);
DISPLAY INVISIBLE (-8900 11800);
FORCEPROP 0 LAST $SEC 1
J 0
(-8900 11800);
DISPLAY 0.680851 (-8900 11800);
PAINT MONO (-8900 11800);
DISPLAY INVISIBLE (-8900 11800);
FORCEPROP 0 LAST CDS_SEC 1
J 0
(-8900 11800);
DISPLAY 1.021277 (-8900 11800);
DISPLAY INVISIBLE (-8900 11800);
FORCEPROP 0 LASTPIN (-9000 11700) $PN 1
R 1
J 0
(-9010 11710);
DISPLAY 0.680851 (-9010 11710);
PAINT MONO (-9010 11710);
FORCEPROP 0 LASTPIN (-9000 11450) $PN 2
R 1
J 2
(-9010 11440);
DISPLAY 0.680851 (-9010 11440);
PAINT MONO (-9010 11440);
FORCEPROP 1 LAST VALUE 0.1UF
J 2
(-8600 11650);
DISPLAY 1.212766 (-8600 11650);
PAINT GREEN (-8600 11650);
FORCEPROP 0 LAST VOLTAGE 25V
J 0
(-8900 11750);
DISPLAY 1.021277 (-8900 11750);
FORCEPROP 0 LAST PACKAGE 0402
J 0
(-8900 11450);
DISPLAY 1.021277 (-8900 11450);
FORCEPROP 1 LAST TOLERANCE 10%
J 2
(-8850 11700);
DISPLAY 1.212766 (-8850 11700);
PAINT GREEN (-8850 11700);
DISPLAY INVISIBLE (-8850 11700);
FORCEPROP 1 LAST CLS_PN G105-0B104-EK
J 2
(-8900 11650);
DISPLAY 1.212766 (-8900 11650);
PAINT GREEN (-8900 11650);
DISPLAY INVISIBLE (-8900 11650);
FORCEPROP 1 LAST CDS_LMAN_SYM_OUTLINE -50,0,50,-50
J 2
(-9000 11600);
DISPLAY 0.468085 (-9000 11600);
PAINT GREEN (-9000 11600);
DISPLAY INVISIBLE (-9000 11600);
FORCEPROP 2 LAST CDS_LIB passive
J 0
(-9000 11600);
DISPLAY INVISIBLE (-9000 11600);
FORCEPROP 1 LAST PATH I374
J 2
(-8900 11650);
DISPLAY 1.212766 (-8900 11650);
PAINT GREEN (-8900 11650);
DISPLAY INVISIBLE (-8900 11650);
FORCEADD CAPACITOR..2
R 2
(-10900 11600);
FORCEPROP 1 LAST $LOCATION C95
J 2
(-10650 11550);
DISPLAY 1.212766 (-10650 11550);
PAINT GREEN (-10650 11550);
FORCEPROP 0 LAST CDS_LOCATION C95
J 0
(-10800 11800);
DISPLAY 1.021277 (-10800 11800);
DISPLAY INVISIBLE (-10800 11800);
FORCEPROP 0 LAST $SEC 1
J 0
(-10800 11800);
DISPLAY 0.680851 (-10800 11800);
PAINT MONO (-10800 11800);
DISPLAY INVISIBLE (-10800 11800);
FORCEPROP 0 LAST CDS_SEC 1
J 0
(-10800 11800);
DISPLAY 1.021277 (-10800 11800);
DISPLAY INVISIBLE (-10800 11800);
FORCEPROP 0 LASTPIN (-10900 11700) $PN 1
R 1
J 0
(-10910 11710);
DISPLAY 0.680851 (-10910 11710);
PAINT MONO (-10910 11710);
FORCEPROP 0 LASTPIN (-10900 11450) $PN 2
R 1
J 2
(-10910 11440);
DISPLAY 0.680851 (-10910 11440);
PAINT MONO (-10910 11440);
FORCEPROP 0 LAST VOLTAGE 25V
J 0
(-10800 11450);
DISPLAY 1.021277 (-10800 11450);
FORCEPROP 1 LAST VALUE 0.1UF
J 2
(-10550 11650);
DISPLAY 1.212766 (-10550 11650);
PAINT GREEN (-10550 11650);
FORCEPROP 0 LAST PACKAGE 0402
J 0
(-10800 11750);
DISPLAY 1.021277 (-10800 11750);
FORCEPROP 2 LAST CDS_LIB passive
J 0
(-10900 11600);
DISPLAY INVISIBLE (-10900 11600);
FORCEPROP 1 LAST CDS_LMAN_SYM_OUTLINE -50,0,50,-50
J 2
(-10900 11600);
DISPLAY 0.468085 (-10900 11600);
PAINT GREEN (-10900 11600);
DISPLAY INVISIBLE (-10900 11600);
FORCEPROP 1 LAST CLS_PN G105-0B104-EK
J 2
(-10800 11650);
DISPLAY 1.212766 (-10800 11650);
PAINT GREEN (-10800 11650);
DISPLAY INVISIBLE (-10800 11650);
FORCEPROP 1 LAST TOLERANCE 10%
J 2
(-10750 11700);
DISPLAY 1.212766 (-10750 11700);
PAINT GREEN (-10750 11700);
DISPLAY INVISIBLE (-10750 11700);
FORCEPROP 1 LAST PATH I375
J 2
(-10800 11650);
DISPLAY 1.212766 (-10800 11650);
PAINT GREEN (-10800 11650);
DISPLAY INVISIBLE (-10800 11650);
FORCEADD CAPACITOR..2
R 2
(-10900 10750);
FORCEPROP 1 LAST $LOCATION C96
J 2
(-11100 10650);
DISPLAY 1.212766 (-11100 10650);
PAINT GREEN (-11100 10650);
FORCEPROP 0 LAST CDS_LOCATION C96
J 0
(-11200 10900);
DISPLAY 1.021277 (-11200 10900);
DISPLAY INVISIBLE (-11200 10900);
FORCEPROP 0 LAST $SEC 1
J 0
(-11200 10900);
DISPLAY 0.680851 (-11200 10900);
PAINT MONO (-11200 10900);
DISPLAY INVISIBLE (-11200 10900);
FORCEPROP 0 LAST CDS_SEC 1
J 0
(-11200 10900);
DISPLAY 1.021277 (-11200 10900);
DISPLAY INVISIBLE (-11200 10900);
FORCEPROP 0 LASTPIN (-10900 10850) $PN 1
R 1
J 0
(-10910 10860);
DISPLAY 0.680851 (-10910 10860);
PAINT MONO (-10910 10860);
FORCEPROP 0 LASTPIN (-10900 10600) $PN 2
R 1
J 2
(-10910 10590);
DISPLAY 0.680851 (-10910 10590);
PAINT MONO (-10910 10590);
FORCEPROP 1 LAST VALUE 0.1UF
J 2
(-10950 10750);
DISPLAY 1.212766 (-10950 10750);
PAINT GREEN (-10950 10750);
FORCEPROP 0 LAST VOLTAGE 25V
J 0
(-11200 10550);
DISPLAY 1.021277 (-11200 10550);
FORCEPROP 0 LAST PACKAGE 0402
J 0
(-11200 10850);
DISPLAY 1.021277 (-11200 10850);
FORCEPROP 2 LAST CDS_LIB passive
J 0
(-10900 10750);
DISPLAY INVISIBLE (-10900 10750);
FORCEPROP 1 LAST CDS_LMAN_SYM_OUTLINE -50,0,50,-50
J 2
(-10900 10750);
DISPLAY 0.468085 (-10900 10750);
PAINT GREEN (-10900 10750);
DISPLAY INVISIBLE (-10900 10750);
FORCEPROP 1 LAST CLS_PN G105-0B104-EK
J 2
(-10800 10800);
DISPLAY 1.212766 (-10800 10800);
PAINT GREEN (-10800 10800);
DISPLAY INVISIBLE (-10800 10800);
FORCEPROP 1 LAST TOLERANCE 10%
J 2
(-10750 10850);
DISPLAY 1.212766 (-10750 10850);
PAINT GREEN (-10750 10850);
DISPLAY INVISIBLE (-10750 10850);
FORCEPROP 1 LAST PATH I376
J 2
(-10800 10800);
DISPLAY 1.212766 (-10800 10800);
PAINT GREEN (-10800 10800);
DISPLAY INVISIBLE (-10800 10800);
FORCEADD CAPACITOR..2
R 2
(-11700 9150);
FORCEPROP 1 LAST $LOCATION C94
J 2
(-11450 9100);
DISPLAY 1.212766 (-11450 9100);
PAINT GREEN (-11450 9100);
FORCEPROP 0 LAST CDS_LOCATION C94
J 0
(-11600 9350);
DISPLAY 1.021277 (-11600 9350);
DISPLAY INVISIBLE (-11600 9350);
FORCEPROP 0 LAST $SEC 1
J 0
(-11600 9350);
DISPLAY 0.680851 (-11600 9350);
PAINT MONO (-11600 9350);
DISPLAY INVISIBLE (-11600 9350);
FORCEPROP 0 LAST CDS_SEC 1
J 0
(-11600 9350);
DISPLAY 1.021277 (-11600 9350);
DISPLAY INVISIBLE (-11600 9350);
FORCEPROP 0 LASTPIN (-11700 9250) $PN 1
R 1
J 0
(-11710 9260);
DISPLAY 0.680851 (-11710 9260);
PAINT MONO (-11710 9260);
FORCEPROP 0 LASTPIN (-11700 9000) $PN 2
R 1
J 2
(-11710 8990);
DISPLAY 0.680851 (-11710 8990);
PAINT MONO (-11710 8990);
FORCEPROP 0 LAST PACKAGE 0402
J 0
(-11600 9300);
DISPLAY 1.021277 (-11600 9300);
FORCEPROP 1 LAST VALUE 0.1UF
J 2
(-11350 9200);
DISPLAY 1.212766 (-11350 9200);
PAINT GREEN (-11350 9200);
FORCEPROP 0 LAST VOLTAGE 25V
J 0
(-11600 9000);
DISPLAY 1.021277 (-11600 9000);
FORCEPROP 1 LAST TOLERANCE 10%
J 2
(-11550 9250);
DISPLAY 1.212766 (-11550 9250);
PAINT GREEN (-11550 9250);
DISPLAY INVISIBLE (-11550 9250);
FORCEPROP 1 LAST CLS_PN G105-0B104-EK
J 2
(-11600 9200);
DISPLAY 1.212766 (-11600 9200);
PAINT GREEN (-11600 9200);
DISPLAY INVISIBLE (-11600 9200);
FORCEPROP 1 LAST CDS_LMAN_SYM_OUTLINE -50,0,50,-50
J 2
(-11700 9150);
DISPLAY 0.468085 (-11700 9150);
PAINT GREEN (-11700 9150);
DISPLAY INVISIBLE (-11700 9150);
FORCEPROP 2 LAST CDS_LIB passive
J 0
(-11700 9150);
DISPLAY INVISIBLE (-11700 9150);
FORCEPROP 1 LAST PATH I377
J 2
(-11600 9200);
DISPLAY 1.212766 (-11600 9200);
PAINT GREEN (-11600 9200);
DISPLAY INVISIBLE (-11600 9200);
FORCEADD CAPACITOR..2
R 2
(-14150 7550);
FORCEPROP 1 LAST $LOCATION C88
J 2
(-13950 7500);
DISPLAY 1.212766 (-13950 7500);
PAINT GREEN (-13950 7500);
FORCEPROP 0 LAST CDS_LOCATION C88
J 0
(-14050 7750);
DISPLAY 1.021277 (-14050 7750);
DISPLAY INVISIBLE (-14050 7750);
FORCEPROP 0 LAST $SEC 1
J 0
(-14050 7750);
DISPLAY 0.680851 (-14050 7750);
PAINT MONO (-14050 7750);
DISPLAY INVISIBLE (-14050 7750);
FORCEPROP 0 LAST CDS_SEC 1
J 0
(-14050 7750);
DISPLAY 1.021277 (-14050 7750);
DISPLAY INVISIBLE (-14050 7750);
FORCEPROP 0 LASTPIN (-14150 7650) $PN 1
R 1
J 0
(-14160 7660);
DISPLAY 0.680851 (-14160 7660);
PAINT MONO (-14160 7660);
FORCEPROP 0 LASTPIN (-14150 7400) $PN 2
R 1
J 2
(-14160 7390);
DISPLAY 0.680851 (-14160 7390);
PAINT MONO (-14160 7390);
FORCEPROP 0 LAST VOLTAGE 25V
J 0
(-14050 7400);
DISPLAY 1.021277 (-14050 7400);
FORCEPROP 1 LAST VALUE 0.1UF
J 2
(-13800 7600);
DISPLAY 1.212766 (-13800 7600);
PAINT GREEN (-13800 7600);
FORCEPROP 0 LAST PACKAGE 0402
J 0
(-14050 7700);
DISPLAY 1.021277 (-14050 7700);
FORCEPROP 1 LAST TOLERANCE 10%
J 2
(-14000 7650);
DISPLAY 1.212766 (-14000 7650);
PAINT GREEN (-14000 7650);
DISPLAY INVISIBLE (-14000 7650);
FORCEPROP 1 LAST CLS_PN G105-0B104-EK
J 2
(-14050 7600);
DISPLAY 1.212766 (-14050 7600);
PAINT GREEN (-14050 7600);
DISPLAY INVISIBLE (-14050 7600);
FORCEPROP 1 LAST CDS_LMAN_SYM_OUTLINE -50,0,50,-50
J 2
(-14150 7550);
DISPLAY 0.468085 (-14150 7550);
PAINT GREEN (-14150 7550);
DISPLAY INVISIBLE (-14150 7550);
FORCEPROP 2 LAST CDS_LIB passive
J 0
(-14150 7550);
DISPLAY INVISIBLE (-14150 7550);
FORCEPROP 1 LAST PATH I378
J 2
(-14050 7600);
DISPLAY 1.212766 (-14050 7600);
PAINT GREEN (-14050 7600);
DISPLAY INVISIBLE (-14050 7600);
FORCEADD CAPACITOR..2
(-9500 11600);
FORCEPROP 1 LAST $LOCATION C98
J 0
(-9400 11550);
DISPLAY 1.212766 (-9400 11550);
PAINT GREEN (-9400 11550);
FORCEPROP 0 LAST CDS_LOCATION C98
J 0
(-9400 11800);
DISPLAY 1.021277 (-9400 11800);
DISPLAY INVISIBLE (-9400 11800);
FORCEPROP 0 LAST $SEC 1
J 0
(-9400 11800);
DISPLAY 0.680851 (-9400 11800);
PAINT MONO (-9400 11800);
DISPLAY INVISIBLE (-9400 11800);
FORCEPROP 0 LAST CDS_SEC 1
J 0
(-9400 11800);
DISPLAY 1.021277 (-9400 11800);
DISPLAY INVISIBLE (-9400 11800);
FORCEPROP 0 LASTPIN (-9500 11700) $PN 1
R 1
J 0
(-9510 11710);
DISPLAY 0.680851 (-9510 11710);
PAINT MONO (-9510 11710);
FORCEPROP 0 LASTPIN (-9500 11450) $PN 2
R 1
J 2
(-9510 11440);
DISPLAY 0.680851 (-9510 11440);
PAINT MONO (-9510 11440);
FORCEPROP 0 LAST VOLTAGE 6.3V
J 0
(-9400 11750);
DISPLAY 1.021277 (-9400 11750);
FORCEPROP 0 LAST PACKAGE 0402
J 0
(-9400 11450);
DISPLAY 1.021277 (-9400 11450);
FORCEPROP 1 LAST VALUE 4.7UF
J 0
(-9400 11650);
DISPLAY 1.212766 (-9400 11650);
PAINT GREEN (-9400 11650);
FORCEPROP 2 LAST CDS_LIB passive
J 0
(-9500 11600);
DISPLAY INVISIBLE (-9500 11600);
FORCEPROP 1 LAST PATH I379
J 0
(-9600 11650);
DISPLAY 1.212766 (-9600 11650);
PAINT GREEN (-9600 11650);
DISPLAY INVISIBLE (-9600 11650);
FORCEPROP 1 LAST CDS_LMAN_SYM_OUTLINE -50,0,50,-50
J 0
(-9500 11600);
DISPLAY 0.468085 (-9500 11600);
PAINT GREEN (-9500 11600);
DISPLAY INVISIBLE (-9500 11600);
FORCEPROP 1 LAST TOLERANCE 20%
J 0
(-9650 11700);
DISPLAY 1.212766 (-9650 11700);
PAINT GREEN (-9650 11700);
DISPLAY INVISIBLE (-9650 11700);
FORCEPROP 1 LAST CLS_PN G105-0F475-BM
J 0
(-9600 11650);
DISPLAY 1.212766 (-9600 11650);
PAINT GREEN (-9600 11650);
DISPLAY INVISIBLE (-9600 11650);
FORCEADD CAPACITOR..2
(-9500 10800);
FORCEPROP 1 LAST $LOCATION C99
J 0
(-9400 10750);
DISPLAY 1.212766 (-9400 10750);
PAINT GREEN (-9400 10750);
FORCEPROP 0 LAST CDS_LOCATION C99
J 0
(-9400 11000);
DISPLAY 1.021277 (-9400 11000);
DISPLAY INVISIBLE (-9400 11000);
FORCEPROP 0 LAST $SEC 1
J 0
(-9400 11000);
DISPLAY 0.680851 (-9400 11000);
PAINT MONO (-9400 11000);
DISPLAY INVISIBLE (-9400 11000);
FORCEPROP 0 LAST CDS_SEC 1
J 0
(-9400 11000);
DISPLAY 1.021277 (-9400 11000);
DISPLAY INVISIBLE (-9400 11000);
FORCEPROP 0 LASTPIN (-9500 10900) $PN 1
R 1
J 0
(-9510 10910);
DISPLAY 0.680851 (-9510 10910);
PAINT MONO (-9510 10910);
FORCEPROP 0 LASTPIN (-9500 10650) $PN 2
R 1
J 2
(-9510 10640);
DISPLAY 0.680851 (-9510 10640);
PAINT MONO (-9510 10640);
FORCEPROP 0 LAST VOLTAGE 6.3V
J 0
(-9400 10950);
DISPLAY 1.021277 (-9400 10950);
FORCEPROP 0 LAST PACKAGE 0402
J 0
(-9400 10650);
DISPLAY 1.021277 (-9400 10650);
FORCEPROP 1 LAST VALUE 4.7UF
J 0
(-9400 10850);
DISPLAY 1.212766 (-9400 10850);
PAINT GREEN (-9400 10850);
FORCEPROP 1 LAST PATH I380
J 0
(-9600 10850);
DISPLAY 1.212766 (-9600 10850);
PAINT GREEN (-9600 10850);
DISPLAY INVISIBLE (-9600 10850);
FORCEPROP 2 LAST CDS_LIB passive
J 0
(-9500 10800);
DISPLAY INVISIBLE (-9500 10800);
FORCEPROP 1 LAST CDS_LMAN_SYM_OUTLINE -50,0,50,-50
J 0
(-9500 10800);
DISPLAY 0.468085 (-9500 10800);
PAINT GREEN (-9500 10800);
DISPLAY INVISIBLE (-9500 10800);
FORCEPROP 1 LAST TOLERANCE 20%
J 0
(-9650 10900);
DISPLAY 1.212766 (-9650 10900);
PAINT GREEN (-9650 10900);
DISPLAY INVISIBLE (-9650 10900);
FORCEPROP 1 LAST CLS_PN G105-0F475-BM
J 0
(-9600 10850);
DISPLAY 1.212766 (-9600 10850);
PAINT GREEN (-9600 10850);
DISPLAY INVISIBLE (-9600 10850);
FORCEADD OFFPAGE_BI..1
(-11900 9850);
FORCEPROP 2 LAST $XR0 24D1<> 
J 0
(-11840 9850);
DISPLAY 0.638298 (-11840 9850);
PAINT MONO (-11840 9850);
FORCEPROP 2 LAST $XR1 24D5<> 
J 0
(-11630 9850);
DISPLAY 0.638298 (-11630 9850);
PAINT MONO (-11630 9850);
FORCEPROP 1 LAST BODY_TYPE COMMENT
J 0
(-11890 9985);
DISPLAY 0.808511 (-11890 9985);
PAINT GREEN (-11890 9985);
DISPLAY INVISIBLE (-11890 9985);
FORCEPROP 1 LAST OFFPAGE TRUE
J 0
(-11890 9905);
DISPLAY 0.808511 (-11890 9905);
PAINT GREEN (-11890 9905);
DISPLAY INVISIBLE (-11890 9905);
FORCEPROP 1 LAST CDS_LMAN_SYM_OUTLINE -50,50,50,-50
J 0
(-11900 9850);
DISPLAY 0.468085 (-11900 9850);
PAINT GREEN (-11900 9850);
DISPLAY INVISIBLE (-11900 9850);
FORCEPROP 2 LAST PATH I384
J 0
(-11850 9950);
DISPLAY 1.021277 (-11850 9950);
DISPLAY INVISIBLE (-11850 9950);
FORCEPROP 2 LAST CDS_LIB cls
J 0
(-11900 9850);
DISPLAY INVISIBLE (-11900 9850);
FORCEADD OFFPAGE_BI..1
(-11900 9750);
FORCEPROP 2 LAST $XR0 24D1<> 
J 0
(-11840 9750);
DISPLAY 0.638298 (-11840 9750);
PAINT MONO (-11840 9750);
FORCEPROP 2 LAST $XR1 24D5<> 
J 0
(-11630 9750);
DISPLAY 0.638298 (-11630 9750);
PAINT MONO (-11630 9750);
FORCEPROP 2 LAST CDS_LIB cls
J 0
(-11900 9750);
DISPLAY INVISIBLE (-11900 9750);
FORCEPROP 2 LAST PATH I385
J 0
(-11850 9850);
DISPLAY 1.021277 (-11850 9850);
DISPLAY INVISIBLE (-11850 9850);
FORCEPROP 1 LAST CDS_LMAN_SYM_OUTLINE -50,50,50,-50
J 0
(-11900 9750);
DISPLAY 0.468085 (-11900 9750);
PAINT GREEN (-11900 9750);
DISPLAY INVISIBLE (-11900 9750);
FORCEPROP 1 LAST OFFPAGE TRUE
J 0
(-11890 9805);
DISPLAY 0.808511 (-11890 9805);
PAINT GREEN (-11890 9805);
DISPLAY INVISIBLE (-11890 9805);
FORCEPROP 1 LAST BODY_TYPE COMMENT
J 0
(-11890 9885);
DISPLAY 0.808511 (-11890 9885);
PAINT GREEN (-11890 9885);
DISPLAY INVISIBLE (-11890 9885);
FORCEADD VCC..1
(-12600 10800);
FORCEPROP 3 LASTPIN (-12550 10750) SIG_NAME XP5R0V_FT4232\g
J 0
(-12540 10760);
DISPLAY 0.659574 (-12540 10760);
PAINT MONO (-12540 10760);
DISPLAY INVISIBLE (-12540 10760);
FORCEPROP 0 LAST VOLTAGE 5V
J 1
(-12550 10900);
DISPLAY 1.021277 (-12550 10900);
DISPLAY BOTH (-12550 10900);
FORCEPROP 1 LAST HDL_POWER XP5R0V_FT4232
J 1
(-12350 10850);
DISPLAY 0.808511 (-12350 10850);
PAINT GREEN (-12350 10850);
FORCEPROP 2 LAST CDS_LIB cls
J 0
(-12600 10800);
DISPLAY INVISIBLE (-12600 10800);
FORCEPROP 1 LAST PATH I386
J 0
(-12565 10890);
DISPLAY 0.808511 (-12565 10890);
PAINT GREEN (-12565 10890);
DISPLAY INVISIBLE (-12565 10890);
FORCEPROP 1 LAST CDS_LMAN_SYM_OUTLINE -250,250,250,-250
J 0
(-12600 10800);
DISPLAY 0.468085 (-12600 10800);
PAINT GREEN (-12600 10800);
DISPLAY INVISIBLE (-12600 10800);
FORCEPROP 1 LAST BODY_TYPE PLUMBING
J 0
(-12645 10757);
DISPLAY 0.340426 (-12645 10757);
PAINT GREEN (-12645 10757);
DISPLAY INVISIBLE (-12645 10757);
FORCEADD OFFPAGE_BI..1
R 2
(-10650 9850);
FORCEPROP 2 LAST $XR0 24D1<> 
J 0
(-10869 9850);
DISPLAY 0.638298 (-10869 9850);
PAINT MONO (-10869 9850);
FORCEPROP 2 LAST $XR1 24D4<> 
J 0
(-11079 9850);
DISPLAY 0.638298 (-11079 9850);
PAINT MONO (-11079 9850);
FORCEPROP 1 LAST OFFPAGE TRUE
J 2
(-10660 9905);
DISPLAY 0.808511 (-10660 9905);
PAINT GREEN (-10660 9905);
DISPLAY INVISIBLE (-10660 9905);
FORCEPROP 1 LAST BODY_TYPE COMMENT
J 2
(-10660 9985);
DISPLAY 0.808511 (-10660 9985);
PAINT GREEN (-10660 9985);
DISPLAY INVISIBLE (-10660 9985);
FORCEPROP 1 LAST CDS_LMAN_SYM_OUTLINE -50,50,50,-50
J 2
(-10650 9850);
DISPLAY 0.468085 (-10650 9850);
PAINT GREEN (-10650 9850);
DISPLAY INVISIBLE (-10650 9850);
FORCEPROP 2 LAST PATH I389
J 2
(-10700 9950);
DISPLAY 1.021277 (-10700 9950);
DISPLAY INVISIBLE (-10700 9950);
FORCEPROP 2 LAST CDS_LIB cls
J 2
(-10650 9850);
DISPLAY INVISIBLE (-10650 9850);
FORCEADD OFFPAGE_BI..1
R 2
(-10650 9750);
FORCEPROP 2 LAST $XR0 24D1<> 
J 0
(-10869 9750);
DISPLAY 0.638298 (-10869 9750);
PAINT MONO (-10869 9750);
FORCEPROP 2 LAST $XR1 24D4<> 
J 0
(-11079 9750);
DISPLAY 0.638298 (-11079 9750);
PAINT MONO (-11079 9750);
FORCEPROP 2 LAST CDS_LIB cls
J 0
(-10650 9750);
DISPLAY INVISIBLE (-10650 9750);
FORCEPROP 2 LAST PATH I390
J 0
(-10600 9850);
DISPLAY 1.021277 (-10600 9850);
DISPLAY INVISIBLE (-10600 9850);
FORCEPROP 1 LAST CDS_LMAN_SYM_OUTLINE -50,50,50,-50
J 2
(-10650 9750);
DISPLAY 0.468085 (-10650 9750);
PAINT GREEN (-10650 9750);
DISPLAY INVISIBLE (-10650 9750);
FORCEPROP 1 LAST OFFPAGE TRUE
J 2
(-10660 9805);
DISPLAY 0.808511 (-10660 9805);
PAINT GREEN (-10660 9805);
DISPLAY INVISIBLE (-10660 9805);
FORCEPROP 1 LAST BODY_TYPE COMMENT
J 2
(-10660 9885);
DISPLAY 0.808511 (-10660 9885);
PAINT GREEN (-10660 9885);
DISPLAY INVISIBLE (-10660 9885);
FORCEADD OFFPAGE_BI..1
R 2
(-14600 9750);
FORCEPROP 2 LAST $XR0 24D4<> 
J 0
(-14819 9750);
DISPLAY 0.638298 (-14819 9750);
PAINT MONO (-14819 9750);
FORCEPROP 2 LAST $XR1 24D5<> 
J 0
(-15029 9750);
DISPLAY 0.638298 (-15029 9750);
PAINT MONO (-15029 9750);
FORCEPROP 2 LAST PATH I391
J 0
(-14550 9850);
DISPLAY 1.021277 (-14550 9850);
DISPLAY INVISIBLE (-14550 9850);
FORCEPROP 2 LAST CDS_LIB cls
J 0
(-14600 9750);
DISPLAY INVISIBLE (-14600 9750);
FORCEPROP 1 LAST CDS_LMAN_SYM_OUTLINE -50,50,50,-50
J 2
(-14600 9750);
DISPLAY 0.468085 (-14600 9750);
PAINT GREEN (-14600 9750);
DISPLAY INVISIBLE (-14600 9750);
FORCEPROP 1 LAST OFFPAGE TRUE
J 2
(-14610 9805);
DISPLAY 0.808511 (-14610 9805);
PAINT GREEN (-14610 9805);
DISPLAY INVISIBLE (-14610 9805);
FORCEPROP 1 LAST BODY_TYPE COMMENT
J 2
(-14610 9885);
DISPLAY 0.808511 (-14610 9885);
PAINT GREEN (-14610 9885);
DISPLAY INVISIBLE (-14610 9885);
FORCEADD OFFPAGE_BI..1
R 2
(-14600 9850);
FORCEPROP 2 LAST $XR0 24D4<> 
J 0
(-14819 9850);
DISPLAY 0.638298 (-14819 9850);
PAINT MONO (-14819 9850);
FORCEPROP 2 LAST $XR1 24D5<> 
J 0
(-15029 9850);
DISPLAY 0.638298 (-15029 9850);
PAINT MONO (-15029 9850);
FORCEPROP 2 LAST PATH I392
J 0
(-14550 9950);
DISPLAY 1.021277 (-14550 9950);
DISPLAY INVISIBLE (-14550 9950);
FORCEPROP 1 LAST OFFPAGE TRUE
J 2
(-14610 9905);
DISPLAY 0.808511 (-14610 9905);
PAINT GREEN (-14610 9905);
DISPLAY INVISIBLE (-14610 9905);
FORCEPROP 1 LAST BODY_TYPE COMMENT
J 2
(-14610 9985);
DISPLAY 0.808511 (-14610 9985);
PAINT GREEN (-14610 9985);
DISPLAY INVISIBLE (-14610 9985);
FORCEPROP 1 LAST CDS_LMAN_SYM_OUTLINE -50,50,50,-50
J 2
(-14600 9850);
DISPLAY 0.468085 (-14600 9850);
PAINT GREEN (-14600 9850);
DISPLAY INVISIBLE (-14600 9850);
FORCEPROP 2 LAST CDS_LIB cls
J 2
(-14600 9850);
DISPLAY INVISIBLE (-14600 9850);
FORCEADD GND_SG..1
(-14050 8750);
FORCEPROP 3 LASTPIN (-14000 8800) SIG_NAME SG\g
J 0
(-13990 8810);
DISPLAY 0.659574 (-13990 8810);
PAINT MONO (-13990 8810);
DISPLAY INVISIBLE (-13990 8810);
FORCEPROP 1 LAST HDL_POWER SG
J 1
(-13995 8655);
DISPLAY 0.808511 (-13995 8655);
PAINT GREEN (-13995 8655);
FORCEPROP 1 LAST BODY_TYPE PLUMBING
J 0
(-14035 8735);
DISPLAY 0.808511 (-14035 8735);
PAINT GREEN (-14035 8735);
DISPLAY INVISIBLE (-14035 8735);
FORCEPROP 1 LAST CDS_LMAN_SYM_OUTLINE 0,0,100,-50
J 0
(-14050 8750);
DISPLAY 0.468085 (-14050 8750);
PAINT GREEN (-14050 8750);
DISPLAY INVISIBLE (-14050 8750);
FORCEPROP 1 LAST PATH I393
J 0
(-14015 8750);
DISPLAY 0.808511 (-14015 8750);
PAINT GREEN (-14015 8750);
DISPLAY INVISIBLE (-14015 8750);
FORCEPROP 2 LAST CDS_LIB cls
J 0
(-14050 8750);
DISPLAY INVISIBLE (-14050 8750);
FORCEADD VCC..1
(-14200 10800);
FORCEPROP 3 LASTPIN (-14150 10750) SIG_NAME XP5R0V_FT4232\g
J 0
(-14140 10760);
DISPLAY 0.659574 (-14140 10760);
PAINT MONO (-14140 10760);
DISPLAY INVISIBLE (-14140 10760);
FORCEPROP 1 LAST HDL_POWER XP5R0V_FT4232
J 1
(-14150 10850);
DISPLAY 0.808511 (-14150 10850);
PAINT GREEN (-14150 10850);
FORCEPROP 0 LAST VOLTAGE 5V
J 1
(-14150 10900);
DISPLAY 1.021277 (-14150 10900);
DISPLAY BOTH (-14150 10900);
FORCEPROP 2 LAST CDS_LIB cls
J 0
(-14200 10800);
DISPLAY INVISIBLE (-14200 10800);
FORCEPROP 1 LAST PATH I394
J 0
(-14165 10890);
DISPLAY 0.808511 (-14165 10890);
PAINT GREEN (-14165 10890);
DISPLAY INVISIBLE (-14165 10890);
FORCEPROP 1 LAST CDS_LMAN_SYM_OUTLINE -250,250,250,-250
J 0
(-14200 10800);
DISPLAY 0.468085 (-14200 10800);
PAINT GREEN (-14200 10800);
DISPLAY INVISIBLE (-14200 10800);
FORCEPROP 1 LAST BODY_TYPE PLUMBING
J 0
(-14245 10757);
DISPLAY 0.340426 (-14245 10757);
PAINT GREEN (-14245 10757);
DISPLAY INVISIBLE (-14245 10757);
FORCEADD RESISTOR..2
R 1
(-12350 10050);
FORCEPROP 1 LAST $LOCATION R445
J 0
(-12650 10100);
DISPLAY 0.978723 (-12650 10100);
PAINT GREEN (-12650 10100);
FORCEPROP 0 LAST CDS_LOCATION R445
R 1
J 0
(-12450 10100);
DISPLAY 1.021277 (-12450 10100);
DISPLAY INVISIBLE (-12450 10100);
FORCEPROP 0 LAST $SEC 1
R 1
J 0
(-12450 10100);
DISPLAY 0.680851 (-12450 10100);
PAINT MONO (-12450 10100);
DISPLAY INVISIBLE (-12450 10100);
FORCEPROP 0 LAST CDS_SEC 1
R 1
J 0
(-12450 10100);
DISPLAY 1.021277 (-12450 10100);
DISPLAY INVISIBLE (-12450 10100);
FORCEPROP 0 LASTPIN (-12450 10050) $PN 1
J 2
(-12460 10060);
DISPLAY 0.680851 (-12460 10060);
PAINT MONO (-12460 10060);
FORCEPROP 0 LASTPIN (-12200 10050) $PN 2
J 0
(-12160 10060);
DISPLAY 0.680851 (-12160 10060);
PAINT MONO (-12160 10060);
FORCEPROP 1 LAST VALUE 5.1KOHM
J 0
(-12150 10100);
DISPLAY 0.978723 (-12150 10100);
PAINT GREEN (-12150 10100);
FORCEPROP 0 LAST PACKAGE 0402
J 0
(-12400 10100);
DISPLAY 0.808511 (-12400 10100);
FORCEPROP 1 LAST CLS_PN G155-05101-01
R 1
J 0
(-12550 9914);
DISPLAY 1.212766 (-12550 9914);
PAINT GREEN (-12550 9914);
DISPLAY INVISIBLE (-12550 9914);
FORCEPROP 1 LAST TOLERANCE 1%
R 1
J 0
(-12605 9853);
DISPLAY 1.212766 (-12605 9853);
PAINT GREEN (-12605 9853);
DISPLAY INVISIBLE (-12605 9853);
FORCEPROP 1 LAST CDS_LMAN_SYM_OUTLINE -50,50,50,-100
R 1
J 0
(-12350 10050);
DISPLAY 0.468085 (-12350 10050);
PAINT GREEN (-12350 10050);
DISPLAY INVISIBLE (-12350 10050);
FORCEPROP 2 LAST CDS_LIB passive
R 1
J 0
(-12350 10050);
DISPLAY INVISIBLE (-12350 10050);
FORCEPROP 1 LAST PATH I395
R 1
J 0
(-12455 9853);
DISPLAY 1.212766 (-12455 9853);
PAINT GREEN (-12455 9853);
DISPLAY INVISIBLE (-12455 9853);
FORCEADD OFFPAGE_OUT..1
(-900 7950);
FORCEPROP 2 LAST $XR0 25C9<> 
J 0
(-845 7950);
DISPLAY 0.638298 (-845 7950);
PAINT MONO (-845 7950);
FORCEPROP 2 LAST $XR1 31D7> 
J 0
(-650 7950);
DISPLAY 0.638298 (-650 7950);
PAINT MONO (-650 7950);
FORCEPROP 2 LAST $XR3 32H7> 
J 0
(-300 7950);
DISPLAY 0.638298 (-300 7950);
PAINT MONO (-300 7950);
FORCEPROP 2 LAST $XR2 31K11> 
J 0
(-480 7950);
DISPLAY 0.638298 (-480 7950);
PAINT MONO (-480 7950);
FORCEPROP 2 LAST $XR4 10F12< 
J 0
(-150 7950);
DISPLAY 0.638298 (-150 7950);
PAINT MONO (-150 7950);
FORCEPROP 1 LAST BODY_TYPE COMMENT
J 0
(-890 8085);
DISPLAY 0.808511 (-890 8085);
PAINT GREEN (-890 8085);
DISPLAY INVISIBLE (-890 8085);
FORCEPROP 1 LAST OFFPAGE TRUE
J 0
(-890 8005);
DISPLAY 0.808511 (-890 8005);
PAINT GREEN (-890 8005);
DISPLAY INVISIBLE (-890 8005);
FORCEPROP 1 LAST CDS_LMAN_SYM_OUTLINE -50,50,50,-50
J 0
(-900 7950);
DISPLAY 0.468085 (-900 7950);
PAINT GREEN (-900 7950);
DISPLAY INVISIBLE (-900 7950);
FORCEPROP 2 LAST PATH I399
J 0
(-850 8050);
DISPLAY 1.021277 (-850 8050);
DISPLAY INVISIBLE (-850 8050);
FORCEPROP 2 LAST CDS_LIB cls
J 0
(-900 7950);
DISPLAY INVISIBLE (-900 7950);
FORCEADD TS3A5018PWR_TSSOP16..1
(-7700 6000);
FORCEPROP 1 LAST $LOCATION U38
J 0
(-7700 6050);
DISPLAY 1.212766 (-7700 6050);
PAINT GREEN (-7700 6050);
FORCEPROP 0 LAST CDS_LOCATION U38
J 0
(-7550 6200);
DISPLAY 1.021277 (-7550 6200);
DISPLAY INVISIBLE (-7550 6200);
FORCEPROP 0 LAST $SEC 1
J 0
(-7550 6200);
DISPLAY 0.680851 (-7550 6200);
PAINT MONO (-7550 6200);
DISPLAY INVISIBLE (-7550 6200);
FORCEPROP 0 LAST CDS_SEC 1
J 0
(-7550 6200);
DISPLAY 1.021277 (-7550 6200);
DISPLAY INVISIBLE (-7550 6200);
FORCEPROP 0 LASTPIN (-7000 5900) $PN 4
J 0
(-6990 5910);
DISPLAY 0.680851 (-6990 5910);
PAINT MONO (-6990 5910);
FORCEPROP 0 LASTPIN (-7000 5600) $PN 7
J 0
(-6990 5610);
DISPLAY 0.680851 (-6990 5610);
PAINT MONO (-6990 5610);
FORCEPROP 0 LASTPIN (-7000 5300) $PN 9
J 0
(-6990 5310);
DISPLAY 0.680851 (-6990 5310);
PAINT MONO (-6990 5310);
FORCEPROP 0 LASTPIN (-7000 5000) $PN 12
J 0
(-6990 5010);
DISPLAY 0.680851 (-6990 5010);
PAINT MONO (-6990 5010);
FORCEPROP 0 LASTPIN (-7800 4600) $PN 15
J 2
(-7810 4610);
DISPLAY 0.680851 (-7810 4610);
PAINT MONO (-7810 4610);
FORCEPROP 0 LASTPIN (-7800 4700) $PN 1
J 2
(-7810 4710);
DISPLAY 0.680851 (-7810 4710);
PAINT MONO (-7810 4710);
FORCEPROP 0 LASTPIN (-7800 5900) $PN 2
J 2
(-7810 5910);
DISPLAY 0.680851 (-7810 5910);
PAINT MONO (-7810 5910);
FORCEPROP 0 LASTPIN (-7800 5600) $PN 5
J 2
(-7810 5610);
DISPLAY 0.680851 (-7810 5610);
PAINT MONO (-7810 5610);
FORCEPROP 0 LASTPIN (-7800 5300) $PN 11
J 2
(-7810 5310);
DISPLAY 0.680851 (-7810 5310);
PAINT MONO (-7810 5310);
FORCEPROP 0 LASTPIN (-7800 5000) $PN 14
J 2
(-7810 5010);
DISPLAY 0.680851 (-7810 5010);
PAINT MONO (-7810 5010);
FORCEPROP 0 LASTPIN (-7800 5800) $PN 3
J 2
(-7810 5810);
DISPLAY 0.680851 (-7810 5810);
PAINT MONO (-7810 5810);
FORCEPROP 0 LASTPIN (-7800 5500) $PN 6
J 2
(-7810 5510);
DISPLAY 0.680851 (-7810 5510);
PAINT MONO (-7810 5510);
FORCEPROP 0 LASTPIN (-7800 5200) $PN 10
J 2
(-7810 5210);
DISPLAY 0.680851 (-7810 5210);
PAINT MONO (-7810 5210);
FORCEPROP 0 LASTPIN (-7800 4900) $PN 13
J 2
(-7810 4910);
DISPLAY 0.680851 (-7810 4910);
PAINT MONO (-7810 4910);
FORCEPROP 0 LAST PART_NUMBER TS3A5018PWR
J 0
(-7550 6150);
DISPLAY 1.021277 (-7550 6150);
FORCEPROP 1 LAST CLS_PN G220-10324-01
J 0
(-7550 6050);
DISPLAY 1.212766 (-7550 6050);
PAINT GREEN (-7550 6050);
FORCEPROP 1 LAST CDS_LMAN_SYM_OUTLINE 0,0,600,-1500
J 0
(-7700 6000);
DISPLAY 0.468085 (-7700 6000);
PAINT GREEN (-7700 6000);
DISPLAY INVISIBLE (-7700 6000);
FORCEPROP 2 LAST CDS_LIB stdlogic
J 0
(-7700 6000);
DISPLAY INVISIBLE (-7700 6000);
FORCEPROP 1 LAST PATH I400
J 0
(-7650 6050);
DISPLAY 1.212766 (-7650 6050);
PAINT GREEN (-7650 6050);
DISPLAY INVISIBLE (-7650 6050);
FORCEADD OFFPAGE_OUT..1
(-5950 5900);
FORCEPROP 2 LAST $XR0 10K8< 
J 0
(-5895 5900);
DISPLAY 0.638298 (-5895 5900);
PAINT MONO (-5895 5900);
FORCEPROP 1 LAST BODY_TYPE COMMENT
J 0
(-5940 6035);
DISPLAY 0.808511 (-5940 6035);
PAINT GREEN (-5940 6035);
DISPLAY INVISIBLE (-5940 6035);
FORCEPROP 1 LAST OFFPAGE TRUE
J 0
(-5940 5955);
DISPLAY 0.808511 (-5940 5955);
PAINT GREEN (-5940 5955);
DISPLAY INVISIBLE (-5940 5955);
FORCEPROP 1 LAST CDS_LMAN_SYM_OUTLINE -50,50,50,-50
J 0
(-5950 5900);
DISPLAY 0.468085 (-5950 5900);
PAINT GREEN (-5950 5900);
DISPLAY INVISIBLE (-5950 5900);
FORCEPROP 2 LAST CDS_LIB cls
J 0
(-5950 5900);
DISPLAY INVISIBLE (-5950 5900);
FORCEPROP 2 LAST PATH I401
J 0
(-5850 5950);
DISPLAY 1.021277 (-5850 5950);
DISPLAY INVISIBLE (-5850 5950);
FORCEADD OFFPAGE_BI..1
(-5950 5600);
FORCEPROP 2 LAST $XR0 10K13<> 
J 0
(-5890 5600);
DISPLAY 0.638298 (-5890 5600);
PAINT MONO (-5890 5600);
FORCEPROP 2 LAST CDS_LIB cls
J 0
(-5950 5600);
DISPLAY INVISIBLE (-5950 5600);
FORCEPROP 1 LAST CDS_LMAN_SYM_OUTLINE -50,50,50,-50
J 0
(-5950 5600);
DISPLAY 0.468085 (-5950 5600);
PAINT GREEN (-5950 5600);
DISPLAY INVISIBLE (-5950 5600);
FORCEPROP 1 LAST OFFPAGE TRUE
J 0
(-5940 5655);
DISPLAY 0.808511 (-5940 5655);
PAINT GREEN (-5940 5655);
DISPLAY INVISIBLE (-5940 5655);
FORCEPROP 1 LAST BODY_TYPE COMMENT
J 0
(-5940 5735);
DISPLAY 0.808511 (-5940 5735);
PAINT GREEN (-5940 5735);
DISPLAY INVISIBLE (-5940 5735);
FORCEPROP 2 LAST PATH I402
J 0
(-5900 5700);
DISPLAY 1.021277 (-5900 5700);
DISPLAY INVISIBLE (-5900 5700);
FORCEADD OFFPAGE_BI..1
(-5950 5300);
FORCEPROP 2 LAST $XR0 10K13<> 
J 0
(-5890 5300);
DISPLAY 0.638298 (-5890 5300);
PAINT MONO (-5890 5300);
FORCEPROP 2 LAST CDS_LIB cls
J 0
(-5950 5300);
DISPLAY INVISIBLE (-5950 5300);
FORCEPROP 1 LAST CDS_LMAN_SYM_OUTLINE -50,50,50,-50
J 0
(-5950 5300);
DISPLAY 0.468085 (-5950 5300);
PAINT GREEN (-5950 5300);
DISPLAY INVISIBLE (-5950 5300);
FORCEPROP 1 LAST OFFPAGE TRUE
J 0
(-5940 5355);
DISPLAY 0.808511 (-5940 5355);
PAINT GREEN (-5940 5355);
DISPLAY INVISIBLE (-5940 5355);
FORCEPROP 1 LAST BODY_TYPE COMMENT
J 0
(-5940 5435);
DISPLAY 0.808511 (-5940 5435);
PAINT GREEN (-5940 5435);
DISPLAY INVISIBLE (-5940 5435);
FORCEPROP 2 LAST PATH I403
J 0
(-5900 5400);
DISPLAY 1.021277 (-5900 5400);
DISPLAY INVISIBLE (-5900 5400);
FORCEADD OFFPAGE_OUT..1
(-5950 5000);
FORCEPROP 2 LAST $XR0 10K8< 
J 0
(-5895 5000);
DISPLAY 0.638298 (-5895 5000);
PAINT MONO (-5895 5000);
FORCEPROP 1 LAST CDS_LMAN_SYM_OUTLINE -50,50,50,-50
J 0
(-5950 5000);
DISPLAY 0.468085 (-5950 5000);
PAINT GREEN (-5950 5000);
DISPLAY INVISIBLE (-5950 5000);
FORCEPROP 2 LAST CDS_LIB cls
J 0
(-5950 5000);
DISPLAY INVISIBLE (-5950 5000);
FORCEPROP 1 LAST BODY_TYPE COMMENT
J 0
(-5940 5135);
DISPLAY 0.808511 (-5940 5135);
PAINT GREEN (-5940 5135);
DISPLAY INVISIBLE (-5940 5135);
FORCEPROP 1 LAST OFFPAGE TRUE
J 0
(-5940 5055);
DISPLAY 0.808511 (-5940 5055);
PAINT GREEN (-5940 5055);
DISPLAY INVISIBLE (-5940 5055);
FORCEPROP 2 LAST PATH I404
J 0
(-5850 5050);
DISPLAY 1.021277 (-5850 5050);
DISPLAY INVISIBLE (-5850 5050);
FORCEADD OFFPAGE_BI..1
(-6100 3700);
FORCEPROP 2 LAST $XR0 10K13<> 
J 0
(-6040 3700);
DISPLAY 0.638298 (-6040 3700);
PAINT MONO (-6040 3700);
FORCEPROP 2 LAST PATH I405
J 0
(-6000 3750);
DISPLAY 1.021277 (-6000 3750);
DISPLAY INVISIBLE (-6000 3750);
FORCEPROP 1 LAST BODY_TYPE COMMENT
J 0
(-6090 3835);
DISPLAY 0.808511 (-6090 3835);
PAINT GREEN (-6090 3835);
DISPLAY INVISIBLE (-6090 3835);
FORCEPROP 1 LAST CDS_LMAN_SYM_OUTLINE -50,50,50,-50
J 0
(-6100 3700);
DISPLAY 0.468085 (-6100 3700);
PAINT GREEN (-6100 3700);
DISPLAY INVISIBLE (-6100 3700);
FORCEPROP 2 LAST CDS_LIB cls
J 0
(-6100 3700);
DISPLAY INVISIBLE (-6100 3700);
FORCEPROP 1 LAST OFFPAGE TRUE
J 0
(-6090 3755);
DISPLAY 0.808511 (-6090 3755);
PAINT GREEN (-6090 3755);
DISPLAY INVISIBLE (-6090 3755);
FORCEADD OFFPAGE_BI..1
(-6100 3050);
FORCEPROP 2 LAST $XR0 10K13<> 
J 0
(-6040 3050);
DISPLAY 0.638298 (-6040 3050);
PAINT MONO (-6040 3050);
FORCEPROP 2 LAST PATH I406
J 0
(-6000 3100);
DISPLAY 1.021277 (-6000 3100);
DISPLAY INVISIBLE (-6000 3100);
FORCEPROP 2 LAST CDS_LIB cls
J 0
(-6100 3050);
DISPLAY INVISIBLE (-6100 3050);
FORCEPROP 1 LAST CDS_LMAN_SYM_OUTLINE -50,50,50,-50
J 0
(-6100 3050);
DISPLAY 0.468085 (-6100 3050);
PAINT GREEN (-6100 3050);
DISPLAY INVISIBLE (-6100 3050);
FORCEPROP 1 LAST BODY_TYPE COMMENT
J 0
(-6090 3185);
DISPLAY 0.808511 (-6090 3185);
PAINT GREEN (-6090 3185);
DISPLAY INVISIBLE (-6090 3185);
FORCEPROP 1 LAST OFFPAGE TRUE
J 0
(-6090 3105);
DISPLAY 0.808511 (-6090 3105);
PAINT GREEN (-6090 3105);
DISPLAY INVISIBLE (-6090 3105);
FORCEADD NLASB3157DFT2G_SC88..1
R 2
(-7100 4000);
FORCEPROP 1 LAST $LOCATION U39
J 2
(-7550 4150);
DISPLAY 1.212766 (-7550 4150);
PAINT GREEN (-7550 4150);
FORCEPROP 0 LAST CDS_LOCATION U39
J 0
(-7600 4250);
DISPLAY 1.021277 (-7600 4250);
DISPLAY INVISIBLE (-7600 4250);
FORCEPROP 0 LAST $SEC 1
J 0
(-7600 4250);
DISPLAY 0.680851 (-7600 4250);
PAINT MONO (-7600 4250);
DISPLAY INVISIBLE (-7600 4250);
FORCEPROP 0 LAST CDS_SEC 1
J 0
(-7600 4250);
DISPLAY 1.021277 (-7600 4250);
DISPLAY INVISIBLE (-7600 4250);
FORCEPROP 0 LASTPIN (-7800 3700) $PN 4
J 2
(-7810 3710);
DISPLAY 0.680851 (-7810 3710);
PAINT MONO (-7810 3710);
FORCEPROP 0 LASTPIN (-7000 3700) $PN 3
J 0
(-6990 3710);
DISPLAY 0.680851 (-6990 3710);
PAINT MONO (-6990 3710);
FORCEPROP 0 LASTPIN (-7000 3900) $PN 1
J 0
(-6990 3910);
DISPLAY 0.680851 (-6990 3910);
PAINT MONO (-6990 3910);
FORCEPROP 0 LASTPIN (-7800 3900) $PN 6
J 2
(-7810 3910);
DISPLAY 0.680851 (-7810 3910);
PAINT MONO (-7810 3910);
FORCEPROP 1 LAST CLS_PN G223-10187-01
J 2
(-6950 4050);
DISPLAY 1.212766 (-6950 4050);
PAINT GREEN (-6950 4050);
FORCEPROP 2 LAST CDS_LIB interface
R 2
J 2
(-7100 4000);
DISPLAY INVISIBLE (-7100 4000);
FORCEPROP 1 LAST CDS_LMAN_SYM_OUTLINE 0,0,600,-400
J 2
(-7100 4000);
DISPLAY 0.468085 (-7100 4000);
PAINT GREEN (-7100 4000);
DISPLAY INVISIBLE (-7100 4000);
FORCEPROP 1 LAST PATH I407
J 2
(-7150 4050);
DISPLAY 1.212766 (-7150 4050);
PAINT GREEN (-7150 4050);
DISPLAY INVISIBLE (-7150 4050);
FORCEADD NLASB3157DFT2G_SC88..1
R 2
(-7100 3350);
FORCEPROP 1 LAST $LOCATION U40
J 2
(-6750 3350);
DISPLAY 1.212766 (-6750 3350);
PAINT GREEN (-6750 3350);
FORCEPROP 0 LAST CDS_LOCATION U40
J 0
(-6800 3450);
DISPLAY 1.021277 (-6800 3450);
DISPLAY INVISIBLE (-6800 3450);
FORCEPROP 0 LAST $SEC 1
J 0
(-6800 3450);
DISPLAY 0.680851 (-6800 3450);
PAINT MONO (-6800 3450);
DISPLAY INVISIBLE (-6800 3450);
FORCEPROP 0 LAST CDS_SEC 1
J 0
(-6800 3450);
DISPLAY 1.021277 (-6800 3450);
DISPLAY INVISIBLE (-6800 3450);
FORCEPROP 0 LASTPIN (-7800 3050) $PN 4
J 2
(-7810 3060);
DISPLAY 0.680851 (-7810 3060);
PAINT MONO (-7810 3060);
FORCEPROP 0 LASTPIN (-7000 3050) $PN 3
J 0
(-6990 3060);
DISPLAY 0.680851 (-6990 3060);
PAINT MONO (-6990 3060);
FORCEPROP 0 LASTPIN (-7000 3250) $PN 1
J 0
(-6990 3260);
DISPLAY 0.680851 (-6990 3260);
PAINT MONO (-6990 3260);
FORCEPROP 0 LASTPIN (-7800 3250) $PN 6
J 2
(-7810 3260);
DISPLAY 0.680851 (-7810 3260);
PAINT MONO (-7810 3260);
FORCEPROP 1 LAST CLS_PN G223-10187-01
J 2
(-6150 3250);
DISPLAY 1.212766 (-6150 3250);
PAINT GREEN (-6150 3250);
FORCEPROP 2 LAST CDS_LIB interface
J 0
(-7100 3350);
DISPLAY INVISIBLE (-7100 3350);
FORCEPROP 1 LAST CDS_LMAN_SYM_OUTLINE 0,0,600,-400
J 2
(-7100 3350);
DISPLAY 0.468085 (-7100 3350);
PAINT GREEN (-7100 3350);
DISPLAY INVISIBLE (-7100 3350);
FORCEPROP 1 LAST PATH I408
J 2
(-7150 3400);
DISPLAY 1.212766 (-7150 3400);
PAINT GREEN (-7150 3400);
DISPLAY INVISIBLE (-7150 3400);
FORCEADD OFFPAGE_IN..2
R 2
(-9000 5900);
FORCEPROP 2 LAST $XR0 10E12> 
J 0
(-9214 5900);
DISPLAY 0.638298 (-9214 5900);
PAINT MONO (-9214 5900);
FORCEPROP 2 LAST CDS_LIB cls
J 0
(-9000 5900);
DISPLAY INVISIBLE (-9000 5900);
FORCEPROP 1 LAST CDS_LMAN_SYM_OUTLINE -50,50,50,-50
J 2
(-9000 5900);
DISPLAY 0.468085 (-9000 5900);
PAINT GREEN (-9000 5900);
DISPLAY INVISIBLE (-9000 5900);
FORCEPROP 1 LAST BODY_TYPE COMMENT
J 2
(-9010 6035);
DISPLAY 0.808511 (-9010 6035);
PAINT GREEN (-9010 6035);
DISPLAY INVISIBLE (-9010 6035);
FORCEPROP 1 LAST OFFPAGE TRUE
J 2
(-9010 5955);
DISPLAY 0.808511 (-9010 5955);
PAINT GREEN (-9010 5955);
DISPLAY INVISIBLE (-9010 5955);
FORCEPROP 2 LAST PATH I409
J 0
(-9150 5950);
DISPLAY 1.021277 (-9150 5950);
DISPLAY INVISIBLE (-9150 5950);
FORCEADD OFFPAGE_BI..1
R 2
(-9000 5600);
FORCEPROP 2 LAST $XR0 11D13<> 
J 0
(-9250 5600);
DISPLAY 0.638298 (-9250 5600);
PAINT MONO (-9250 5600);
FORCEPROP 1 LAST BODY_TYPE COMMENT
J 2
(-9010 5735);
DISPLAY 0.808511 (-9010 5735);
PAINT GREEN (-9010 5735);
DISPLAY INVISIBLE (-9010 5735);
FORCEPROP 1 LAST OFFPAGE TRUE
J 2
(-9010 5655);
DISPLAY 0.808511 (-9010 5655);
PAINT GREEN (-9010 5655);
DISPLAY INVISIBLE (-9010 5655);
FORCEPROP 1 LAST CDS_LMAN_SYM_OUTLINE -50,50,50,-50
J 2
(-9000 5600);
DISPLAY 0.468085 (-9000 5600);
PAINT GREEN (-9000 5600);
DISPLAY INVISIBLE (-9000 5600);
FORCEPROP 2 LAST CDS_LIB cls
J 0
(-9000 5600);
DISPLAY INVISIBLE (-9000 5600);
FORCEPROP 2 LAST PATH I410
J 0
(-8950 5700);
DISPLAY 1.021277 (-8950 5700);
DISPLAY INVISIBLE (-8950 5700);
FORCEADD RESISTOR..1
(-8550 4700);
FORCEPROP 1 LAST $LOCATION R461
J 2
(-8750 4700);
DISPLAY 1.212766 (-8750 4700);
PAINT GREEN (-8750 4700);
FORCEPROP 0 LAST CDS_LOCATION R461
J 0
(-8350 4800);
DISPLAY 1.021277 (-8350 4800);
DISPLAY INVISIBLE (-8350 4800);
FORCEPROP 0 LAST $SEC 1
J 0
(-8350 4800);
DISPLAY 0.680851 (-8350 4800);
PAINT MONO (-8350 4800);
DISPLAY INVISIBLE (-8350 4800);
FORCEPROP 0 LAST CDS_SEC 1
J 0
(-8350 4800);
DISPLAY 1.021277 (-8350 4800);
DISPLAY INVISIBLE (-8350 4800);
FORCEPROP 0 LASTPIN (-8650 4700) $PN 1
J 2
(-8660 4710);
DISPLAY 0.680851 (-8660 4710);
PAINT MONO (-8660 4710);
FORCEPROP 0 LASTPIN (-8400 4700) $PN 2
J 0
(-8390 4710);
DISPLAY 0.680851 (-8390 4710);
PAINT MONO (-8390 4710);
FORCEPROP 1 LAST VALUE 33OHM
J 0
(-8350 4700);
DISPLAY 1.212766 (-8350 4700);
PAINT GREEN (-8350 4700);
FORCEPROP 0 LAST NO_ASSY TRUE
J 0
(-8750 4750);
DISPLAY 0.808511 (-8750 4750);
DISPLAY BOTH (-8750 4750);
FORCEPROP 0 LAST PACKAGE 0402
J 0
(-8600 4650);
DISPLAY 0.808511 (-8600 4650);
FORCEPROP 1 LAST PATH I411
J 0
(-8747 4805);
DISPLAY 1.212766 (-8747 4805);
PAINT GREEN (-8747 4805);
DISPLAY INVISIBLE (-8747 4805);
FORCEPROP 1 LAST TOLERANCE 1%
J 0
(-8747 4955);
DISPLAY 1.212766 (-8747 4955);
PAINT GREEN (-8747 4955);
DISPLAY INVISIBLE (-8747 4955);
FORCEPROP 2 LAST CDS_LIB passive
J 0
(-8550 4700);
DISPLAY INVISIBLE (-8550 4700);
FORCEPROP 1 LAST CDS_LMAN_SYM_OUTLINE -50,50,100,-50
J 0
(-8550 4700);
DISPLAY 0.468085 (-8550 4700);
PAINT GREEN (-8550 4700);
DISPLAY INVISIBLE (-8550 4700);
FORCEPROP 1 LAST CLS_PN G155-133R0-01
J 0
(-8686 4900);
DISPLAY 1.212766 (-8686 4900);
PAINT GREEN (-8686 4900);
DISPLAY INVISIBLE (-8686 4900);
FORCEADD RESISTOR..1
(-8550 4600);
FORCEPROP 1 LAST $LOCATION R462
J 2
(-8750 4600);
DISPLAY 1.212766 (-8750 4600);
PAINT GREEN (-8750 4600);
FORCEPROP 0 LAST CDS_LOCATION R462
J 0
(-8350 4700);
DISPLAY 1.021277 (-8350 4700);
DISPLAY INVISIBLE (-8350 4700);
FORCEPROP 0 LAST $SEC 1
J 0
(-8350 4700);
DISPLAY 0.680851 (-8350 4700);
PAINT MONO (-8350 4700);
DISPLAY INVISIBLE (-8350 4700);
FORCEPROP 0 LAST CDS_SEC 1
J 0
(-8350 4700);
DISPLAY 1.021277 (-8350 4700);
DISPLAY INVISIBLE (-8350 4700);
FORCEPROP 0 LASTPIN (-8650 4600) $PN 1
J 2
(-8660 4610);
DISPLAY 0.680851 (-8660 4610);
PAINT MONO (-8660 4610);
FORCEPROP 0 LASTPIN (-8400 4600) $PN 2
J 0
(-8390 4610);
DISPLAY 0.680851 (-8390 4610);
PAINT MONO (-8390 4610);
FORCEPROP 1 LAST VALUE 33OHM
J 0
(-8350 4600);
DISPLAY 1.212766 (-8350 4600);
PAINT GREEN (-8350 4600);
FORCEPROP 0 LAST PACKAGE 0402
J 0
(-8600 4550);
DISPLAY 0.808511 (-8600 4550);
FORCEPROP 1 LAST PATH I412
J 0
(-8747 4705);
DISPLAY 1.212766 (-8747 4705);
PAINT GREEN (-8747 4705);
DISPLAY INVISIBLE (-8747 4705);
FORCEPROP 1 LAST CLS_PN G155-133R0-01
J 0
(-8686 4800);
DISPLAY 1.212766 (-8686 4800);
PAINT GREEN (-8686 4800);
DISPLAY INVISIBLE (-8686 4800);
FORCEPROP 1 LAST CDS_LMAN_SYM_OUTLINE -50,50,100,-50
J 0
(-8550 4600);
DISPLAY 0.468085 (-8550 4600);
PAINT GREEN (-8550 4600);
DISPLAY INVISIBLE (-8550 4600);
FORCEPROP 2 LAST CDS_LIB passive
J 0
(-8550 4600);
DISPLAY INVISIBLE (-8550 4600);
FORCEPROP 1 LAST TOLERANCE 1%
J 0
(-8747 4855);
DISPLAY 1.212766 (-8747 4855);
PAINT GREEN (-8747 4855);
DISPLAY INVISIBLE (-8747 4855);
FORCEADD OFFPAGE_BI..1
R 2
(-9000 5300);
FORCEPROP 2 LAST $XR0 11D13<> 
J 0
(-9250 5300);
DISPLAY 0.638298 (-9250 5300);
PAINT MONO (-9250 5300);
FORCEPROP 1 LAST BODY_TYPE COMMENT
J 2
(-9010 5435);
DISPLAY 0.808511 (-9010 5435);
PAINT GREEN (-9010 5435);
DISPLAY INVISIBLE (-9010 5435);
FORCEPROP 1 LAST OFFPAGE TRUE
J 2
(-9010 5355);
DISPLAY 0.808511 (-9010 5355);
PAINT GREEN (-9010 5355);
DISPLAY INVISIBLE (-9010 5355);
FORCEPROP 1 LAST CDS_LMAN_SYM_OUTLINE -50,50,50,-50
J 2
(-9000 5300);
DISPLAY 0.468085 (-9000 5300);
PAINT GREEN (-9000 5300);
DISPLAY INVISIBLE (-9000 5300);
FORCEPROP 2 LAST CDS_LIB cls
J 0
(-9000 5300);
DISPLAY INVISIBLE (-9000 5300);
FORCEPROP 2 LAST PATH I413
J 0
(-8950 5400);
DISPLAY 1.021277 (-8950 5400);
DISPLAY INVISIBLE (-8950 5400);
FORCEADD OFFPAGE_IN..2
R 2
(-9000 5000);
FORCEPROP 2 LAST $XR0 11E13> 
J 0
(-9214 5000);
DISPLAY 0.638298 (-9214 5000);
PAINT MONO (-9214 5000);
FORCEPROP 2 LAST CDS_LIB cls
J 0
(-9000 5000);
DISPLAY INVISIBLE (-9000 5000);
FORCEPROP 1 LAST CDS_LMAN_SYM_OUTLINE -50,50,50,-50
J 2
(-9000 5000);
DISPLAY 0.468085 (-9000 5000);
PAINT GREEN (-9000 5000);
DISPLAY INVISIBLE (-9000 5000);
FORCEPROP 1 LAST BODY_TYPE COMMENT
J 2
(-9010 5135);
DISPLAY 0.808511 (-9010 5135);
PAINT GREEN (-9010 5135);
DISPLAY INVISIBLE (-9010 5135);
FORCEPROP 1 LAST OFFPAGE TRUE
J 2
(-9010 5055);
DISPLAY 0.808511 (-9010 5055);
PAINT GREEN (-9010 5055);
DISPLAY INVISIBLE (-9010 5055);
FORCEPROP 2 LAST PATH I414
J 0
(-9200 5050);
DISPLAY 1.021277 (-9200 5050);
DISPLAY INVISIBLE (-9200 5050);
FORCEADD OFFPAGE_IN..2
R 2
(-9900 4700);
FORCEPROP 2 LAST $XR0 12D5> 
J 0
(-10083 4700);
DISPLAY 0.638298 (-10083 4700);
PAINT MONO (-10083 4700);
FORCEPROP 1 LAST OFFPAGE TRUE
J 2
(-9910 4755);
DISPLAY 0.808511 (-9910 4755);
PAINT GREEN (-9910 4755);
DISPLAY INVISIBLE (-9910 4755);
FORCEPROP 1 LAST BODY_TYPE COMMENT
J 2
(-9910 4835);
DISPLAY 0.808511 (-9910 4835);
PAINT GREEN (-9910 4835);
DISPLAY INVISIBLE (-9910 4835);
FORCEPROP 1 LAST CDS_LMAN_SYM_OUTLINE -50,50,50,-50
J 2
(-9900 4700);
DISPLAY 0.468085 (-9900 4700);
PAINT GREEN (-9900 4700);
DISPLAY INVISIBLE (-9900 4700);
FORCEPROP 2 LAST CDS_LIB cls
J 0
(-9900 4700);
DISPLAY INVISIBLE (-9900 4700);
FORCEPROP 2 LAST PATH I415
J 0
(-10050 4750);
DISPLAY 1.021277 (-10050 4750);
DISPLAY INVISIBLE (-10050 4750);
FORCEADD OFFPAGE_IN..2
R 2
(-9900 4600);
FORCEPROP 2 LAST $XR0 24C10> 
J 0
(-10114 4600);
DISPLAY 0.638298 (-10114 4600);
PAINT MONO (-10114 4600);
FORCEPROP 1 LAST OFFPAGE TRUE
J 2
(-9910 4655);
DISPLAY 0.808511 (-9910 4655);
PAINT GREEN (-9910 4655);
DISPLAY INVISIBLE (-9910 4655);
FORCEPROP 1 LAST BODY_TYPE COMMENT
J 2
(-9910 4735);
DISPLAY 0.808511 (-9910 4735);
PAINT GREEN (-9910 4735);
DISPLAY INVISIBLE (-9910 4735);
FORCEPROP 2 LAST PATH I416
J 0
(-10100 4650);
DISPLAY 1.021277 (-10100 4650);
DISPLAY INVISIBLE (-10100 4650);
FORCEPROP 1 LAST CDS_LMAN_SYM_OUTLINE -50,50,50,-50
J 2
(-9900 4600);
DISPLAY 0.468085 (-9900 4600);
PAINT GREEN (-9900 4600);
DISPLAY INVISIBLE (-9900 4600);
FORCEPROP 2 LAST CDS_LIB cls
J 0
(-9900 4600);
DISPLAY INVISIBLE (-9900 4600);
FORCEADD OFFPAGE_OUT..1
(-11500 5900);
FORCEPROP 2 LAST $XR0 10J2< 
J 0
(-11445 5900);
DISPLAY 0.638298 (-11445 5900);
PAINT MONO (-11445 5900);
FORCEPROP 2 LAST PATH I417
J 0
(-11400 5950);
DISPLAY 1.021277 (-11400 5950);
DISPLAY INVISIBLE (-11400 5950);
FORCEPROP 1 LAST CDS_LMAN_SYM_OUTLINE -50,50,50,-50
J 0
(-11500 5900);
DISPLAY 0.468085 (-11500 5900);
PAINT GREEN (-11500 5900);
DISPLAY INVISIBLE (-11500 5900);
FORCEPROP 2 LAST CDS_LIB cls
J 0
(-11500 5900);
DISPLAY INVISIBLE (-11500 5900);
FORCEPROP 1 LAST BODY_TYPE COMMENT
J 0
(-11490 6035);
DISPLAY 0.808511 (-11490 6035);
PAINT GREEN (-11490 6035);
DISPLAY INVISIBLE (-11490 6035);
FORCEPROP 1 LAST OFFPAGE TRUE
J 0
(-11490 5955);
DISPLAY 0.808511 (-11490 5955);
PAINT GREEN (-11490 5955);
DISPLAY INVISIBLE (-11490 5955);
FORCEADD OFFPAGE_OUT..1
(-11500 5600);
FORCEPROP 2 LAST $XR0 10K2< 
J 0
(-11445 5600);
DISPLAY 0.638298 (-11445 5600);
PAINT MONO (-11445 5600);
FORCEPROP 2 LAST PATH I418
J 0
(-11400 5650);
DISPLAY 1.021277 (-11400 5650);
DISPLAY INVISIBLE (-11400 5650);
FORCEPROP 1 LAST CDS_LMAN_SYM_OUTLINE -50,50,50,-50
J 0
(-11500 5600);
DISPLAY 0.468085 (-11500 5600);
PAINT GREEN (-11500 5600);
DISPLAY INVISIBLE (-11500 5600);
FORCEPROP 2 LAST CDS_LIB cls
J 0
(-11500 5600);
DISPLAY INVISIBLE (-11500 5600);
FORCEPROP 1 LAST BODY_TYPE COMMENT
J 0
(-11490 5735);
DISPLAY 0.808511 (-11490 5735);
PAINT GREEN (-11490 5735);
DISPLAY INVISIBLE (-11490 5735);
FORCEPROP 1 LAST OFFPAGE TRUE
J 0
(-11490 5655);
DISPLAY 0.808511 (-11490 5655);
PAINT GREEN (-11490 5655);
DISPLAY INVISIBLE (-11490 5655);
FORCEADD OFFPAGE_IN..2
(-10600 4600);
FORCEPROP 2 LAST $XR0 24C10> 
J 0
(-10545 4600);
DISPLAY 0.638298 (-10545 4600);
PAINT MONO (-10545 4600);
FORCEPROP 1 LAST BODY_TYPE COMMENT
J 0
(-10590 4735);
DISPLAY 0.808511 (-10590 4735);
PAINT GREEN (-10590 4735);
DISPLAY INVISIBLE (-10590 4735);
FORCEPROP 1 LAST OFFPAGE TRUE
J 0
(-10590 4655);
DISPLAY 0.808511 (-10590 4655);
PAINT GREEN (-10590 4655);
DISPLAY INVISIBLE (-10590 4655);
FORCEPROP 2 LAST PATH I419
J 0
(-10500 4650);
DISPLAY 1.021277 (-10500 4650);
DISPLAY INVISIBLE (-10500 4650);
FORCEPROP 2 LAST CDS_LIB cls
J 0
(-10600 4600);
DISPLAY INVISIBLE (-10600 4600);
FORCEPROP 1 LAST CDS_LMAN_SYM_OUTLINE -50,50,50,-50
J 0
(-10600 4600);
DISPLAY 0.468085 (-10600 4600);
PAINT GREEN (-10600 4600);
DISPLAY INVISIBLE (-10600 4600);
FORCEADD OFFPAGE_IN..2
(-10600 4700);
FORCEPROP 2 LAST $XR0 12D5> 
J 0
(-10545 4700);
DISPLAY 0.638298 (-10545 4700);
PAINT MONO (-10545 4700);
FORCEPROP 2 LAST PATH I420
J 0
(-10500 4750);
DISPLAY 1.021277 (-10500 4750);
DISPLAY INVISIBLE (-10500 4750);
FORCEPROP 2 LAST CDS_LIB cls
J 0
(-10600 4700);
DISPLAY INVISIBLE (-10600 4700);
FORCEPROP 1 LAST CDS_LMAN_SYM_OUTLINE -50,50,50,-50
J 0
(-10600 4700);
DISPLAY 0.468085 (-10600 4700);
PAINT GREEN (-10600 4700);
DISPLAY INVISIBLE (-10600 4700);
FORCEPROP 1 LAST BODY_TYPE COMMENT
J 0
(-10590 4835);
DISPLAY 0.808511 (-10590 4835);
PAINT GREEN (-10590 4835);
DISPLAY INVISIBLE (-10590 4835);
FORCEPROP 1 LAST OFFPAGE TRUE
J 0
(-10590 4755);
DISPLAY 0.808511 (-10590 4755);
PAINT GREEN (-10590 4755);
DISPLAY INVISIBLE (-10590 4755);
FORCEADD OFFPAGE_IN..2
(-11500 5300);
FORCEPROP 2 LAST $XR0 10J2> 
J 0
(-11445 5300);
DISPLAY 0.638298 (-11445 5300);
PAINT MONO (-11445 5300);
FORCEPROP 2 LAST PATH I421
J 0
(-11400 5350);
DISPLAY 1.021277 (-11400 5350);
DISPLAY INVISIBLE (-11400 5350);
FORCEPROP 2 LAST CDS_LIB cls
J 0
(-11500 5300);
DISPLAY INVISIBLE (-11500 5300);
FORCEPROP 1 LAST CDS_LMAN_SYM_OUTLINE -50,50,50,-50
J 0
(-11500 5300);
DISPLAY 0.468085 (-11500 5300);
PAINT GREEN (-11500 5300);
DISPLAY INVISIBLE (-11500 5300);
FORCEPROP 1 LAST BODY_TYPE COMMENT
J 0
(-11490 5435);
DISPLAY 0.808511 (-11490 5435);
PAINT GREEN (-11490 5435);
DISPLAY INVISIBLE (-11490 5435);
FORCEPROP 1 LAST OFFPAGE TRUE
J 0
(-11490 5355);
DISPLAY 0.808511 (-11490 5355);
PAINT GREEN (-11490 5355);
DISPLAY INVISIBLE (-11490 5355);
FORCEADD OFFPAGE_OUT..1
(-11500 5000);
FORCEPROP 2 LAST $XR0 10J2< 
J 0
(-11445 5000);
DISPLAY 0.638298 (-11445 5000);
PAINT MONO (-11445 5000);
FORCEPROP 1 LAST OFFPAGE TRUE
J 0
(-11490 5055);
DISPLAY 0.808511 (-11490 5055);
PAINT GREEN (-11490 5055);
DISPLAY INVISIBLE (-11490 5055);
FORCEPROP 1 LAST BODY_TYPE COMMENT
J 0
(-11490 5135);
DISPLAY 0.808511 (-11490 5135);
PAINT GREEN (-11490 5135);
DISPLAY INVISIBLE (-11490 5135);
FORCEPROP 2 LAST PATH I422
J 0
(-11400 5050);
DISPLAY 1.021277 (-11400 5050);
DISPLAY INVISIBLE (-11400 5050);
FORCEPROP 2 LAST CDS_LIB cls
J 0
(-11500 5000);
DISPLAY INVISIBLE (-11500 5000);
FORCEPROP 1 LAST CDS_LMAN_SYM_OUTLINE -50,50,50,-50
J 0
(-11500 5000);
DISPLAY 0.468085 (-11500 5000);
PAINT GREEN (-11500 5000);
DISPLAY INVISIBLE (-11500 5000);
FORCEADD RESISTOR..1
(-12000 4700);
FORCEPROP 1 LAST $LOCATION R448
J 2
(-12150 4700);
DISPLAY 1.212766 (-12150 4700);
PAINT GREEN (-12150 4700);
FORCEPROP 0 LAST CDS_LOCATION R448
J 0
(-11800 4800);
DISPLAY 1.021277 (-11800 4800);
DISPLAY INVISIBLE (-11800 4800);
FORCEPROP 0 LAST $SEC 1
J 0
(-11800 4800);
DISPLAY 0.680851 (-11800 4800);
PAINT MONO (-11800 4800);
DISPLAY INVISIBLE (-11800 4800);
FORCEPROP 0 LAST CDS_SEC 1
J 0
(-11800 4800);
DISPLAY 1.021277 (-11800 4800);
DISPLAY INVISIBLE (-11800 4800);
FORCEPROP 0 LASTPIN (-12100 4700) $PN 1
J 2
(-12110 4710);
DISPLAY 0.680851 (-12110 4710);
PAINT MONO (-12110 4710);
FORCEPROP 0 LASTPIN (-11850 4700) $PN 2
J 0
(-11840 4710);
DISPLAY 0.680851 (-11840 4710);
PAINT MONO (-11840 4710);
FORCEPROP 1 LAST VALUE 33OHM
J 0
(-11800 4700);
DISPLAY 1.212766 (-11800 4700);
PAINT GREEN (-11800 4700);
FORCEPROP 0 LAST NO_ASSY TRUE
J 0
(-12100 4750);
DISPLAY 0.808511 (-12100 4750);
DISPLAY BOTH (-12100 4750);
FORCEPROP 0 LAST PACKAGE 0402
J 0
(-12050 4700);
DISPLAY 0.808511 (-12050 4700);
FORCEPROP 1 LAST PATH I423
J 0
(-12197 4805);
DISPLAY 1.212766 (-12197 4805);
PAINT GREEN (-12197 4805);
DISPLAY INVISIBLE (-12197 4805);
FORCEPROP 2 LAST CDS_LIB passive
J 0
(-12000 4700);
DISPLAY INVISIBLE (-12000 4700);
FORCEPROP 1 LAST CDS_LMAN_SYM_OUTLINE -50,50,100,-50
J 0
(-12000 4700);
DISPLAY 0.468085 (-12000 4700);
PAINT GREEN (-12000 4700);
DISPLAY INVISIBLE (-12000 4700);
FORCEPROP 1 LAST CLS_PN G155-133R0-01
J 0
(-12136 4900);
DISPLAY 1.212766 (-12136 4900);
PAINT GREEN (-12136 4900);
DISPLAY INVISIBLE (-12136 4900);
FORCEPROP 1 LAST TOLERANCE 1%
J 0
(-12197 4955);
DISPLAY 1.212766 (-12197 4955);
PAINT GREEN (-12197 4955);
DISPLAY INVISIBLE (-12197 4955);
FORCEADD RESISTOR..1
(-12000 4600);
FORCEPROP 1 LAST $LOCATION R449
J 2
(-12150 4600);
DISPLAY 1.212766 (-12150 4600);
PAINT GREEN (-12150 4600);
FORCEPROP 0 LAST CDS_LOCATION R449
J 0
(-11800 4700);
DISPLAY 1.021277 (-11800 4700);
DISPLAY INVISIBLE (-11800 4700);
FORCEPROP 0 LAST $SEC 1
J 0
(-11800 4700);
DISPLAY 0.680851 (-11800 4700);
PAINT MONO (-11800 4700);
DISPLAY INVISIBLE (-11800 4700);
FORCEPROP 0 LAST CDS_SEC 1
J 0
(-11800 4700);
DISPLAY 1.021277 (-11800 4700);
DISPLAY INVISIBLE (-11800 4700);
FORCEPROP 0 LASTPIN (-12100 4600) $PN 1
J 2
(-12110 4610);
DISPLAY 0.680851 (-12110 4610);
PAINT MONO (-12110 4610);
FORCEPROP 0 LASTPIN (-11850 4600) $PN 2
J 0
(-11840 4610);
DISPLAY 0.680851 (-11840 4610);
PAINT MONO (-11840 4610);
FORCEPROP 1 LAST VALUE 33OHM
J 0
(-11800 4600);
DISPLAY 1.212766 (-11800 4600);
PAINT GREEN (-11800 4600);
FORCEPROP 0 LAST PACKAGE 0402
J 0
(-12050 4600);
DISPLAY 0.808511 (-12050 4600);
FORCEPROP 1 LAST PATH I424
J 0
(-12197 4705);
DISPLAY 1.212766 (-12197 4705);
PAINT GREEN (-12197 4705);
DISPLAY INVISIBLE (-12197 4705);
FORCEPROP 2 LAST CDS_LIB passive
J 0
(-12000 4600);
DISPLAY INVISIBLE (-12000 4600);
FORCEPROP 1 LAST CDS_LMAN_SYM_OUTLINE -50,50,100,-50
J 0
(-12000 4600);
DISPLAY 0.468085 (-12000 4600);
PAINT GREEN (-12000 4600);
DISPLAY INVISIBLE (-12000 4600);
FORCEPROP 1 LAST CLS_PN G155-133R0-01
J 0
(-12136 4800);
DISPLAY 1.212766 (-12136 4800);
PAINT GREEN (-12136 4800);
DISPLAY INVISIBLE (-12136 4800);
FORCEPROP 1 LAST TOLERANCE 1%
J 0
(-12197 4855);
DISPLAY 1.212766 (-12197 4855);
PAINT GREEN (-12197 4855);
DISPLAY INVISIBLE (-12197 4855);
FORCEADD TS3A5018PWR_TSSOP16..1
R 2
(-12650 6000);
FORCEPROP 1 LAST $LOCATION U30
J 2
(-13150 6050);
DISPLAY 1.212766 (-13150 6050);
PAINT GREEN (-13150 6050);
FORCEPROP 0 LAST CDS_LOCATION U30
J 0
(-13050 6200);
DISPLAY 1.021277 (-13050 6200);
DISPLAY INVISIBLE (-13050 6200);
FORCEPROP 0 LAST $SEC 1
J 0
(-13050 6200);
DISPLAY 0.680851 (-13050 6200);
PAINT MONO (-13050 6200);
DISPLAY INVISIBLE (-13050 6200);
FORCEPROP 0 LAST CDS_SEC 1
J 0
(-13050 6200);
DISPLAY 1.021277 (-13050 6200);
DISPLAY INVISIBLE (-13050 6200);
FORCEPROP 0 LASTPIN (-13350 5900) $PN 4
J 2
(-13360 5910);
DISPLAY 0.680851 (-13360 5910);
PAINT MONO (-13360 5910);
FORCEPROP 0 LASTPIN (-13350 5600) $PN 7
J 2
(-13360 5610);
DISPLAY 0.680851 (-13360 5610);
PAINT MONO (-13360 5610);
FORCEPROP 0 LASTPIN (-13350 5300) $PN 9
J 2
(-13360 5310);
DISPLAY 0.680851 (-13360 5310);
PAINT MONO (-13360 5310);
FORCEPROP 0 LASTPIN (-13350 5000) $PN 12
J 2
(-13360 5010);
DISPLAY 0.680851 (-13360 5010);
PAINT MONO (-13360 5010);
FORCEPROP 0 LASTPIN (-12550 4600) $PN 15
J 0
(-12540 4610);
DISPLAY 0.680851 (-12540 4610);
PAINT MONO (-12540 4610);
FORCEPROP 0 LASTPIN (-12550 4700) $PN 1
J 0
(-12540 4710);
DISPLAY 0.680851 (-12540 4710);
PAINT MONO (-12540 4710);
FORCEPROP 0 LASTPIN (-12550 5900) $PN 2
J 0
(-12540 5910);
DISPLAY 0.680851 (-12540 5910);
PAINT MONO (-12540 5910);
FORCEPROP 0 LASTPIN (-12550 5600) $PN 5
J 0
(-12540 5610);
DISPLAY 0.680851 (-12540 5610);
PAINT MONO (-12540 5610);
FORCEPROP 0 LASTPIN (-12550 5300) $PN 11
J 0
(-12540 5310);
DISPLAY 0.680851 (-12540 5310);
PAINT MONO (-12540 5310);
FORCEPROP 0 LASTPIN (-12550 5000) $PN 14
J 0
(-12540 5010);
DISPLAY 0.680851 (-12540 5010);
PAINT MONO (-12540 5010);
FORCEPROP 0 LASTPIN (-12550 5800) $PN 3
J 0
(-12540 5810);
DISPLAY 0.680851 (-12540 5810);
PAINT MONO (-12540 5810);
FORCEPROP 0 LASTPIN (-12550 5500) $PN 6
J 0
(-12540 5510);
DISPLAY 0.680851 (-12540 5510);
PAINT MONO (-12540 5510);
FORCEPROP 0 LASTPIN (-12550 5200) $PN 10
J 0
(-12540 5210);
DISPLAY 0.680851 (-12540 5210);
PAINT MONO (-12540 5210);
FORCEPROP 0 LASTPIN (-12550 4900) $PN 13
J 0
(-12540 4910);
DISPLAY 0.680851 (-12540 4910);
PAINT MONO (-12540 4910);
FORCEPROP 0 LAST PART_NUMBER TS3A5018PWR
J 0
(-13050 6150);
DISPLAY 1.021277 (-13050 6150);
FORCEPROP 1 LAST CLS_PN G220-10324-01
J 2
(-12300 6050);
DISPLAY 1.212766 (-12300 6050);
PAINT GREEN (-12300 6050);
FORCEPROP 1 LAST PATH I425
J 2
(-12700 6050);
DISPLAY 1.212766 (-12700 6050);
PAINT GREEN (-12700 6050);
DISPLAY INVISIBLE (-12700 6050);
FORCEPROP 2 LAST CDS_LIB stdlogic
J 2
(-12650 6000);
DISPLAY INVISIBLE (-12650 6000);
FORCEPROP 1 LAST CDS_LMAN_SYM_OUTLINE 0,0,600,-1500
J 2
(-12650 6000);
DISPLAY 0.468085 (-12650 6000);
PAINT GREEN (-12650 6000);
DISPLAY INVISIBLE (-12650 6000);
FORCEADD OFFPAGE_IN..2
R 2
(-14450 5900);
FORCEPROP 2 LAST $XR0 24B13> 
J 0
(-14664 5900);
DISPLAY 0.638298 (-14664 5900);
PAINT MONO (-14664 5900);
FORCEPROP 2 LAST CDS_LIB cls
J 0
(-14450 5900);
DISPLAY INVISIBLE (-14450 5900);
FORCEPROP 1 LAST CDS_LMAN_SYM_OUTLINE -50,50,50,-50
J 2
(-14450 5900);
DISPLAY 0.468085 (-14450 5900);
PAINT GREEN (-14450 5900);
DISPLAY INVISIBLE (-14450 5900);
FORCEPROP 1 LAST BODY_TYPE COMMENT
J 2
(-14460 6035);
DISPLAY 0.808511 (-14460 6035);
PAINT GREEN (-14460 6035);
DISPLAY INVISIBLE (-14460 6035);
FORCEPROP 1 LAST OFFPAGE TRUE
J 2
(-14460 5955);
DISPLAY 0.808511 (-14460 5955);
PAINT GREEN (-14460 5955);
DISPLAY INVISIBLE (-14460 5955);
FORCEPROP 2 LAST PATH I426
J 0
(-14650 5950);
DISPLAY 1.021277 (-14650 5950);
DISPLAY INVISIBLE (-14650 5950);
FORCEADD OFFPAGE_IN..2
R 2
(-14450 5600);
FORCEPROP 2 LAST $XR0 24B13> 
J 0
(-14664 5600);
DISPLAY 0.638298 (-14664 5600);
PAINT MONO (-14664 5600);
FORCEPROP 1 LAST CDS_LMAN_SYM_OUTLINE -50,50,50,-50
J 2
(-14450 5600);
DISPLAY 0.468085 (-14450 5600);
PAINT GREEN (-14450 5600);
DISPLAY INVISIBLE (-14450 5600);
FORCEPROP 2 LAST CDS_LIB cls
J 0
(-14450 5600);
DISPLAY INVISIBLE (-14450 5600);
FORCEPROP 1 LAST OFFPAGE TRUE
J 2
(-14460 5655);
DISPLAY 0.808511 (-14460 5655);
PAINT GREEN (-14460 5655);
DISPLAY INVISIBLE (-14460 5655);
FORCEPROP 1 LAST BODY_TYPE COMMENT
J 2
(-14460 5735);
DISPLAY 0.808511 (-14460 5735);
PAINT GREEN (-14460 5735);
DISPLAY INVISIBLE (-14460 5735);
FORCEPROP 2 LAST PATH I427
J 0
(-14650 5650);
DISPLAY 1.021277 (-14650 5650);
DISPLAY INVISIBLE (-14650 5650);
FORCEADD OFFPAGE_OUT..1
R 2
(-14450 5300);
FORCEPROP 2 LAST $XR0 24B13< 
J 0
(-14664 5300);
DISPLAY 0.638298 (-14664 5300);
PAINT MONO (-14664 5300);
FORCEPROP 2 LAST CDS_LIB cls
J 2
(-14450 5300);
DISPLAY INVISIBLE (-14450 5300);
FORCEPROP 1 LAST CDS_LMAN_SYM_OUTLINE -50,50,50,-50
J 2
(-14450 5300);
DISPLAY 0.468085 (-14450 5300);
PAINT GREEN (-14450 5300);
DISPLAY INVISIBLE (-14450 5300);
FORCEPROP 1 LAST BODY_TYPE COMMENT
J 2
(-14460 5435);
DISPLAY 0.808511 (-14460 5435);
PAINT GREEN (-14460 5435);
DISPLAY INVISIBLE (-14460 5435);
FORCEPROP 1 LAST OFFPAGE TRUE
J 2
(-14460 5355);
DISPLAY 0.808511 (-14460 5355);
PAINT GREEN (-14460 5355);
DISPLAY INVISIBLE (-14460 5355);
FORCEPROP 2 LAST PATH I428
J 0
(-14650 5350);
DISPLAY 1.021277 (-14650 5350);
DISPLAY INVISIBLE (-14650 5350);
FORCEADD OFFPAGE_IN..2
R 2
(-14450 5000);
FORCEPROP 2 LAST $XR0 24C13> 
J 0
(-14664 5000);
DISPLAY 0.638298 (-14664 5000);
PAINT MONO (-14664 5000);
FORCEPROP 1 LAST BODY_TYPE COMMENT
J 2
(-14460 5135);
DISPLAY 0.808511 (-14460 5135);
PAINT GREEN (-14460 5135);
DISPLAY INVISIBLE (-14460 5135);
FORCEPROP 1 LAST OFFPAGE TRUE
J 2
(-14460 5055);
DISPLAY 0.808511 (-14460 5055);
PAINT GREEN (-14460 5055);
DISPLAY INVISIBLE (-14460 5055);
FORCEPROP 2 LAST CDS_LIB cls
J 2
(-14450 5000);
DISPLAY INVISIBLE (-14450 5000);
FORCEPROP 1 LAST CDS_LMAN_SYM_OUTLINE -50,50,50,-50
J 2
(-14450 5000);
DISPLAY 0.468085 (-14450 5000);
PAINT GREEN (-14450 5000);
DISPLAY INVISIBLE (-14450 5000);
FORCEPROP 2 LAST PATH I429
J 0
(-14650 5050);
DISPLAY 1.021277 (-14650 5050);
DISPLAY INVISIBLE (-14650 5050);
FORCEADD RESISTOR..2
R 1
(-8800 4100);
FORCEPROP 1 LAST $LOCATION R458
J 0
(-9150 4100);
DISPLAY 1.212766 (-9150 4100);
PAINT GREEN (-9150 4100);
FORCEPROP 0 LAST CDS_LOCATION R458
R 1
J 0
(-8600 4200);
DISPLAY 1.021277 (-8600 4200);
DISPLAY INVISIBLE (-8600 4200);
FORCEPROP 0 LAST $SEC 1
R 1
J 0
(-8600 4200);
DISPLAY 0.680851 (-8600 4200);
PAINT MONO (-8600 4200);
DISPLAY INVISIBLE (-8600 4200);
FORCEPROP 0 LAST CDS_SEC 1
R 1
J 0
(-8600 4200);
DISPLAY 1.021277 (-8600 4200);
DISPLAY INVISIBLE (-8600 4200);
FORCEPROP 0 LASTPIN (-8900 4100) $PN 1
J 2
(-8910 4110);
DISPLAY 0.680851 (-8910 4110);
PAINT MONO (-8910 4110);
FORCEPROP 0 LASTPIN (-8650 4100) $PN 2
J 0
(-8640 4110);
DISPLAY 0.680851 (-8640 4110);
PAINT MONO (-8640 4110);
FORCEPROP 1 LAST VALUE 1KOHM
J 0
(-8600 4100);
DISPLAY 1.212766 (-8600 4100);
PAINT GREEN (-8600 4100);
FORCEPROP 0 LAST PACKAGE 0402
J 0
(-8850 4150);
DISPLAY 0.808511 (-8850 4150);
FORCEPROP 1 LAST PATH I430
R 1
J 0
(-8905 3903);
DISPLAY 1.212766 (-8905 3903);
PAINT GREEN (-8905 3903);
DISPLAY INVISIBLE (-8905 3903);
FORCEPROP 1 LAST CLS_PN G155-11001-01
R 1
J 0
(-9000 3964);
DISPLAY 1.212766 (-9000 3964);
PAINT GREEN (-9000 3964);
DISPLAY INVISIBLE (-9000 3964);
FORCEPROP 1 LAST TOLERANCE 1%
R 1
J 0
(-9055 3903);
DISPLAY 1.212766 (-9055 3903);
PAINT GREEN (-9055 3903);
DISPLAY INVISIBLE (-9055 3903);
FORCEPROP 1 LAST CDS_LMAN_SYM_OUTLINE -50,50,50,-100
R 1
J 0
(-8800 4100);
DISPLAY 0.468085 (-8800 4100);
PAINT GREEN (-8800 4100);
DISPLAY INVISIBLE (-8800 4100);
FORCEPROP 2 LAST CDS_LIB passive
J 0
(-8800 4100);
DISPLAY INVISIBLE (-8800 4100);
FORCEADD RESISTOR..2
R 1
(-8800 4200);
FORCEPROP 1 LAST $LOCATION R457
J 0
(-9150 4200);
DISPLAY 1.212766 (-9150 4200);
PAINT GREEN (-9150 4200);
FORCEPROP 0 LAST CDS_LOCATION R457
R 1
J 0
(-8600 4300);
DISPLAY 1.021277 (-8600 4300);
DISPLAY INVISIBLE (-8600 4300);
FORCEPROP 0 LAST $SEC 1
R 1
J 0
(-8600 4300);
DISPLAY 0.680851 (-8600 4300);
PAINT MONO (-8600 4300);
DISPLAY INVISIBLE (-8600 4300);
FORCEPROP 0 LAST CDS_SEC 1
R 1
J 0
(-8600 4300);
DISPLAY 1.021277 (-8600 4300);
DISPLAY INVISIBLE (-8600 4300);
FORCEPROP 0 LASTPIN (-8900 4200) $PN 1
J 2
(-8910 4210);
DISPLAY 0.680851 (-8910 4210);
PAINT MONO (-8910 4210);
FORCEPROP 0 LASTPIN (-8650 4200) $PN 2
J 0
(-8640 4210);
DISPLAY 0.680851 (-8640 4210);
PAINT MONO (-8640 4210);
FORCEPROP 1 LAST VALUE 4.7KOHM
J 0
(-8600 4200);
DISPLAY 1.212766 (-8600 4200);
PAINT GREEN (-8600 4200);
FORCEPROP 0 LAST PACKAGE 0402
J 0
(-8850 4250);
DISPLAY 0.808511 (-8850 4250);
FORCEPROP 0 LAST NO_ASSY TRUE
J 0
(-9700 4200);
DISPLAY 0.808511 (-9700 4200);
DISPLAY BOTH (-9700 4200);
FORCEPROP 1 LAST PATH I431
R 1
J 0
(-8905 4003);
DISPLAY 1.212766 (-8905 4003);
PAINT GREEN (-8905 4003);
DISPLAY INVISIBLE (-8905 4003);
FORCEPROP 2 LAST CDS_LIB passive
J 0
(-8800 4200);
DISPLAY INVISIBLE (-8800 4200);
FORCEPROP 1 LAST CDS_LMAN_SYM_OUTLINE -50,50,50,-100
R 1
J 0
(-8800 4200);
DISPLAY 0.468085 (-8800 4200);
PAINT GREEN (-8800 4200);
DISPLAY INVISIBLE (-8800 4200);
FORCEPROP 1 LAST CLS_PN G155-14701-01
R 1
J 0
(-9000 4064);
DISPLAY 1.212766 (-9000 4064);
PAINT GREEN (-9000 4064);
DISPLAY INVISIBLE (-9000 4064);
FORCEPROP 1 LAST TOLERANCE 1%
R 1
J 0
(-9055 4003);
DISPLAY 1.212766 (-9055 4003);
PAINT GREEN (-9055 4003);
DISPLAY INVISIBLE (-9055 4003);
FORCEADD RESISTOR..2
R 1
(-8800 4000);
FORCEPROP 1 LAST $LOCATION R459
J 0
(-9150 4000);
DISPLAY 1.212766 (-9150 4000);
PAINT GREEN (-9150 4000);
FORCEPROP 0 LAST CDS_LOCATION R459
R 1
J 0
(-8600 4100);
DISPLAY 1.021277 (-8600 4100);
DISPLAY INVISIBLE (-8600 4100);
FORCEPROP 0 LAST $SEC 1
R 1
J 0
(-8600 4100);
DISPLAY 0.680851 (-8600 4100);
PAINT MONO (-8600 4100);
DISPLAY INVISIBLE (-8600 4100);
FORCEPROP 0 LAST CDS_SEC 1
R 1
J 0
(-8600 4100);
DISPLAY 1.021277 (-8600 4100);
DISPLAY INVISIBLE (-8600 4100);
FORCEPROP 0 LASTPIN (-8900 4000) $PN 1
J 2
(-8910 4010);
DISPLAY 0.680851 (-8910 4010);
PAINT MONO (-8910 4010);
FORCEPROP 0 LASTPIN (-8650 4000) $PN 2
J 0
(-8640 4010);
DISPLAY 0.680851 (-8640 4010);
PAINT MONO (-8640 4010);
FORCEPROP 1 LAST VALUE 1KOHM
J 0
(-8600 4000);
DISPLAY 1.212766 (-8600 4000);
PAINT GREEN (-8600 4000);
FORCEPROP 0 LAST PACKAGE 0402
J 0
(-8850 4050);
DISPLAY 0.808511 (-8850 4050);
FORCEPROP 1 LAST PATH I432
R 1
J 0
(-8905 3803);
DISPLAY 1.212766 (-8905 3803);
PAINT GREEN (-8905 3803);
DISPLAY INVISIBLE (-8905 3803);
FORCEPROP 1 LAST CLS_PN G155-11001-01
R 1
J 0
(-9000 3864);
DISPLAY 1.212766 (-9000 3864);
PAINT GREEN (-9000 3864);
DISPLAY INVISIBLE (-9000 3864);
FORCEPROP 1 LAST TOLERANCE 1%
R 1
J 0
(-9055 3803);
DISPLAY 1.212766 (-9055 3803);
PAINT GREEN (-9055 3803);
DISPLAY INVISIBLE (-9055 3803);
FORCEPROP 1 LAST CDS_LMAN_SYM_OUTLINE -50,50,50,-100
R 1
J 0
(-8800 4000);
DISPLAY 0.468085 (-8800 4000);
PAINT GREEN (-8800 4000);
DISPLAY INVISIBLE (-8800 4000);
FORCEPROP 2 LAST CDS_LIB passive
J 0
(-8800 4000);
DISPLAY INVISIBLE (-8800 4000);
FORCEPROP 2 LASTPIN (-8650 4000) SIG_NAME UN$524$RESISTOR$I432$2
J 0
(-8640 4010);
DISPLAY 0.659574 (-8640 4010);
PAINT MONO (-8640 4010);
DISPLAY INVISIBLE (-8640 4010);
FORCEADD OFFPAGE_BI..1
R 2
(-8900 3700);
FORCEPROP 2 LAST $XR0 11D13<> 
J 0
(-9150 3700);
DISPLAY 0.638298 (-9150 3700);
PAINT MONO (-9150 3700);
FORCEPROP 2 LAST CDS_LIB cls
J 2
(-8900 3700);
DISPLAY INVISIBLE (-8900 3700);
FORCEPROP 1 LAST CDS_LMAN_SYM_OUTLINE -50,50,50,-50
J 2
(-8900 3700);
DISPLAY 0.468085 (-8900 3700);
PAINT GREEN (-8900 3700);
DISPLAY INVISIBLE (-8900 3700);
FORCEPROP 1 LAST OFFPAGE TRUE
J 2
(-8910 3755);
DISPLAY 0.808511 (-8910 3755);
PAINT GREEN (-8910 3755);
DISPLAY INVISIBLE (-8910 3755);
FORCEPROP 1 LAST BODY_TYPE COMMENT
J 2
(-8910 3835);
DISPLAY 0.808511 (-8910 3835);
PAINT GREEN (-8910 3835);
DISPLAY INVISIBLE (-8910 3835);
FORCEPROP 2 LAST PATH I433
J 0
(-8850 3800);
DISPLAY 1.021277 (-8850 3800);
DISPLAY INVISIBLE (-8850 3800);
FORCEADD VCC..1
(-9300 4300);
FORCEPROP 3 LASTPIN (-9250 4250) SIG_NAME XP3R3V_FPGA\g
J 0
(-9240 4260);
DISPLAY 0.659574 (-9240 4260);
PAINT MONO (-9240 4260);
DISPLAY INVISIBLE (-9240 4260);
FORCEPROP 0 LAST VOLTAGE 3.3V
J 0
(-9500 4400);
DISPLAY 1.021277 (-9500 4400);
DISPLAY BOTH (-9500 4400);
FORCEPROP 1 LAST HDL_POWER XP3R3V_FPGA
J 1
(-9245 4355);
DISPLAY 1.021277 (-9245 4355);
PAINT GREEN (-9245 4355);
FORCEPROP 1 LAST PATH I434
J 0
(-9265 4390);
DISPLAY 0.808511 (-9265 4390);
PAINT GREEN (-9265 4390);
DISPLAY INVISIBLE (-9265 4390);
FORCEPROP 1 LAST BODY_TYPE PLUMBING
J 0
(-9345 4257);
DISPLAY 0.340426 (-9345 4257);
PAINT GREEN (-9345 4257);
DISPLAY INVISIBLE (-9345 4257);
FORCEPROP 2 LAST CDS_LIB cls
J 0
(-9300 4300);
DISPLAY INVISIBLE (-9300 4300);
FORCEPROP 1 LAST CDS_LMAN_SYM_OUTLINE -250,250,250,-250
J 0
(-9300 4300);
DISPLAY 0.468085 (-9300 4300);
PAINT GREEN (-9300 4300);
DISPLAY INVISIBLE (-9300 4300);
FORCEADD GND_SG..1
(-9250 3900);
FORCEPROP 3 LASTPIN (-9200 3950) SIG_NAME SG\g
J 0
(-9190 3960);
DISPLAY 0.659574 (-9190 3960);
PAINT MONO (-9190 3960);
DISPLAY INVISIBLE (-9190 3960);
FORCEPROP 0 LAST VOLTAGE 0
J 0
(-9150 3900);
DISPLAY 1.021277 (-9150 3900);
FORCEPROP 1 LAST HDL_POWER SG
J 1
(-9195 3805);
DISPLAY 0.808511 (-9195 3805);
PAINT GREEN (-9195 3805);
FORCEPROP 1 LAST PATH I435
J 0
(-9215 3900);
DISPLAY 0.808511 (-9215 3900);
PAINT GREEN (-9215 3900);
DISPLAY INVISIBLE (-9215 3900);
FORCEPROP 1 LAST CDS_LMAN_SYM_OUTLINE 0,0,100,-50
J 0
(-9250 3900);
DISPLAY 0.468085 (-9250 3900);
PAINT GREEN (-9250 3900);
DISPLAY INVISIBLE (-9250 3900);
FORCEPROP 2 LAST CDS_LIB cls
J 0
(-9250 3900);
DISPLAY INVISIBLE (-9250 3900);
FORCEPROP 1 LAST BODY_TYPE PLUMBING
J 0
(-9235 3885);
DISPLAY 0.808511 (-9235 3885);
PAINT GREEN (-9235 3885);
DISPLAY INVISIBLE (-9235 3885);
FORCEADD OFFPAGE_BI..1
R 2
(-8900 3050);
FORCEPROP 2 LAST $XR0 11D13<> 
J 0
(-9150 3050);
DISPLAY 0.638298 (-9150 3050);
PAINT MONO (-9150 3050);
FORCEPROP 2 LAST PATH I436
J 0
(-8850 3150);
DISPLAY 1.021277 (-8850 3150);
DISPLAY INVISIBLE (-8850 3150);
FORCEPROP 1 LAST OFFPAGE TRUE
J 2
(-8910 3105);
DISPLAY 0.808511 (-8910 3105);
PAINT GREEN (-8910 3105);
DISPLAY INVISIBLE (-8910 3105);
FORCEPROP 1 LAST BODY_TYPE COMMENT
J 2
(-8910 3185);
DISPLAY 0.808511 (-8910 3185);
PAINT GREEN (-8910 3185);
DISPLAY INVISIBLE (-8910 3185);
FORCEPROP 1 LAST CDS_LMAN_SYM_OUTLINE -50,50,50,-50
J 2
(-8900 3050);
DISPLAY 0.468085 (-8900 3050);
PAINT GREEN (-8900 3050);
DISPLAY INVISIBLE (-8900 3050);
FORCEPROP 2 LAST CDS_LIB cls
J 0
(-8900 3050);
DISPLAY INVISIBLE (-8900 3050);
FORCEADD VCC..1
(-11350 4300);
FORCEPROP 3 LASTPIN (-11300 4250) SIG_NAME XP3R3V_FPGA\g
J 0
(-11290 4260);
DISPLAY 0.659574 (-11290 4260);
PAINT MONO (-11290 4260);
DISPLAY INVISIBLE (-11290 4260);
FORCEPROP 0 LAST VOLTAGE 3.3V
J 0
(-11550 4400);
DISPLAY 1.021277 (-11550 4400);
DISPLAY BOTH (-11550 4400);
FORCEPROP 1 LAST HDL_POWER XP3R3V_FPGA
J 1
(-11295 4355);
DISPLAY 1.021277 (-11295 4355);
PAINT GREEN (-11295 4355);
FORCEPROP 1 LAST PATH I437
J 0
(-11315 4390);
DISPLAY 0.808511 (-11315 4390);
PAINT GREEN (-11315 4390);
DISPLAY INVISIBLE (-11315 4390);
FORCEPROP 2 LAST CDS_LIB cls
J 0
(-11350 4300);
DISPLAY INVISIBLE (-11350 4300);
FORCEPROP 1 LAST CDS_LMAN_SYM_OUTLINE -250,250,250,-250
J 0
(-11350 4300);
DISPLAY 0.468085 (-11350 4300);
PAINT GREEN (-11350 4300);
DISPLAY INVISIBLE (-11350 4300);
FORCEPROP 1 LAST BODY_TYPE PLUMBING
J 0
(-11395 4257);
DISPLAY 0.340426 (-11395 4257);
PAINT GREEN (-11395 4257);
DISPLAY INVISIBLE (-11395 4257);
FORCEADD GND_SG..1
(-11400 3750);
FORCEPROP 3 LASTPIN (-11350 3800) SIG_NAME SG\g
J 0
(-11340 3810);
DISPLAY 0.659574 (-11340 3810);
PAINT MONO (-11340 3810);
DISPLAY INVISIBLE (-11340 3810);
FORCEPROP 1 LAST HDL_POWER SG
J 1
(-11345 3655);
DISPLAY 0.808511 (-11345 3655);
PAINT GREEN (-11345 3655);
FORCEPROP 0 LAST VOLTAGE 0
J 0
(-11300 3750);
DISPLAY 1.021277 (-11300 3750);
FORCEPROP 1 LAST PATH I438
J 0
(-11365 3750);
DISPLAY 0.808511 (-11365 3750);
PAINT GREEN (-11365 3750);
DISPLAY INVISIBLE (-11365 3750);
FORCEPROP 1 LAST BODY_TYPE PLUMBING
J 0
(-11385 3735);
DISPLAY 0.808511 (-11385 3735);
PAINT GREEN (-11385 3735);
DISPLAY INVISIBLE (-11385 3735);
FORCEPROP 2 LAST CDS_LIB cls
J 0
(-11400 3750);
DISPLAY INVISIBLE (-11400 3750);
FORCEPROP 1 LAST CDS_LMAN_SYM_OUTLINE 0,0,100,-50
J 0
(-11400 3750);
DISPLAY 0.468085 (-11400 3750);
PAINT GREEN (-11400 3750);
DISPLAY INVISIBLE (-11400 3750);
FORCEADD OFFPAGE_BI..1
(-11150 3450);
FORCEPROP 2 LAST $XR0 11D5<> 
J 0
(-11090 3450);
DISPLAY 0.638298 (-11090 3450);
PAINT MONO (-11090 3450);
FORCEPROP 1 LAST BODY_TYPE COMMENT
J 0
(-11140 3585);
DISPLAY 0.808511 (-11140 3585);
PAINT GREEN (-11140 3585);
DISPLAY INVISIBLE (-11140 3585);
FORCEPROP 1 LAST OFFPAGE TRUE
J 0
(-11140 3505);
DISPLAY 0.808511 (-11140 3505);
PAINT GREEN (-11140 3505);
DISPLAY INVISIBLE (-11140 3505);
FORCEPROP 2 LAST PATH I439
J 0
(-11050 3500);
DISPLAY 1.021277 (-11050 3500);
DISPLAY INVISIBLE (-11050 3500);
FORCEPROP 1 LAST CDS_LMAN_SYM_OUTLINE -50,50,50,-50
J 0
(-11150 3450);
DISPLAY 0.468085 (-11150 3450);
PAINT GREEN (-11150 3450);
DISPLAY INVISIBLE (-11150 3450);
FORCEPROP 2 LAST CDS_LIB cls
J 0
(-11150 3450);
DISPLAY INVISIBLE (-11150 3450);
FORCEADD VCC..1
(-11350 9950);
FORCEPROP 3 LASTPIN (-11300 9900) SIG_NAME XP5R0V_FT4232\g
J 0
(-11290 9910);
DISPLAY 0.659574 (-11290 9910);
PAINT MONO (-11290 9910);
DISPLAY INVISIBLE (-11290 9910);
FORCEPROP 0 LAST VOLTAGE 5V
J 1
(-11300 10050);
DISPLAY 1.021277 (-11300 10050);
DISPLAY BOTH (-11300 10050);
FORCEPROP 1 LAST HDL_POWER XP5R0V_FT4232
J 1
(-11300 10000);
DISPLAY 0.808511 (-11300 10000);
PAINT GREEN (-11300 10000);
FORCEPROP 1 LAST PATH I44
J 0
(-11315 10040);
DISPLAY 0.808511 (-11315 10040);
PAINT GREEN (-11315 10040);
DISPLAY INVISIBLE (-11315 10040);
FORCEPROP 1 LAST BODY_TYPE PLUMBING
J 0
(-11395 9907);
DISPLAY 0.340426 (-11395 9907);
PAINT GREEN (-11395 9907);
DISPLAY INVISIBLE (-11395 9907);
FORCEPROP 1 LAST CDS_LMAN_SYM_OUTLINE -250,250,250,-250
J 0
(-11350 9950);
DISPLAY 0.468085 (-11350 9950);
PAINT GREEN (-11350 9950);
DISPLAY INVISIBLE (-11350 9950);
FORCEPROP 2 LAST CDS_LIB cls
J 0
(-11350 9950);
DISPLAY INVISIBLE (-11350 9950);
FORCEADD RESISTOR..2
R 1
(-12000 4200);
FORCEPROP 1 LAST $LOCATION R450
J 0
(-12350 4200);
DISPLAY 1.212766 (-12350 4200);
PAINT GREEN (-12350 4200);
FORCEPROP 0 LAST CDS_LOCATION R450
R 1
J 0
(-11750 4300);
DISPLAY 1.021277 (-11750 4300);
DISPLAY INVISIBLE (-11750 4300);
FORCEPROP 0 LAST $SEC 1
R 1
J 0
(-11750 4300);
DISPLAY 0.680851 (-11750 4300);
PAINT MONO (-11750 4300);
DISPLAY INVISIBLE (-11750 4300);
FORCEPROP 0 LAST CDS_SEC 1
R 1
J 0
(-11750 4300);
DISPLAY 1.021277 (-11750 4300);
DISPLAY INVISIBLE (-11750 4300);
FORCEPROP 0 LASTPIN (-12100 4200) $PN 1
J 2
(-12110 4210);
DISPLAY 0.680851 (-12110 4210);
PAINT MONO (-12110 4210);
FORCEPROP 0 LASTPIN (-11850 4200) $PN 2
J 0
(-11840 4210);
DISPLAY 0.680851 (-11840 4210);
PAINT MONO (-11840 4210);
FORCEPROP 0 LAST PACKAGE 0402
J 0
(-12050 4250);
DISPLAY 0.808511 (-12050 4250);
FORCEPROP 1 LAST VALUE 4.7KOHM
J 0
(-11750 4200);
DISPLAY 1.212766 (-11750 4200);
PAINT GREEN (-11750 4200);
FORCEPROP 1 LAST PATH I440
R 1
J 0
(-12105 4003);
DISPLAY 1.212766 (-12105 4003);
PAINT GREEN (-12105 4003);
DISPLAY INVISIBLE (-12105 4003);
FORCEPROP 2 LAST CDS_LIB passive
J 0
(-12000 4200);
DISPLAY INVISIBLE (-12000 4200);
FORCEPROP 1 LAST CDS_LMAN_SYM_OUTLINE -50,50,50,-100
R 1
J 0
(-12000 4200);
DISPLAY 0.468085 (-12000 4200);
PAINT GREEN (-12000 4200);
DISPLAY INVISIBLE (-12000 4200);
FORCEPROP 1 LAST CLS_PN G155-14701-01
R 1
J 0
(-12200 4064);
DISPLAY 1.212766 (-12200 4064);
PAINT GREEN (-12200 4064);
DISPLAY INVISIBLE (-12200 4064);
FORCEPROP 1 LAST TOLERANCE 1%
R 1
J 0
(-12255 4003);
DISPLAY 1.212766 (-12255 4003);
PAINT GREEN (-12255 4003);
DISPLAY INVISIBLE (-12255 4003);
FORCEADD RESISTOR..2
R 1
(-12000 4100);
FORCEPROP 1 LAST $LOCATION R451
J 0
(-12350 4100);
DISPLAY 1.212766 (-12350 4100);
PAINT GREEN (-12350 4100);
FORCEPROP 0 LAST CDS_LOCATION R451
R 1
J 0
(-11750 4200);
DISPLAY 1.021277 (-11750 4200);
DISPLAY INVISIBLE (-11750 4200);
FORCEPROP 0 LAST $SEC 1
R 1
J 0
(-11750 4200);
DISPLAY 0.680851 (-11750 4200);
PAINT MONO (-11750 4200);
DISPLAY INVISIBLE (-11750 4200);
FORCEPROP 0 LAST CDS_SEC 1
R 1
J 0
(-11750 4200);
DISPLAY 1.021277 (-11750 4200);
DISPLAY INVISIBLE (-11750 4200);
FORCEPROP 0 LASTPIN (-12100 4100) $PN 1
J 2
(-12110 4110);
DISPLAY 0.680851 (-12110 4110);
PAINT MONO (-12110 4110);
FORCEPROP 0 LASTPIN (-11850 4100) $PN 2
J 0
(-11840 4110);
DISPLAY 0.680851 (-11840 4110);
PAINT MONO (-11840 4110);
FORCEPROP 0 LAST PACKAGE 0402
J 0
(-12050 4150);
DISPLAY 0.808511 (-12050 4150);
FORCEPROP 0 LAST NO_ASSY TRUE
J 0
(-11400 4100);
DISPLAY 0.808511 (-11400 4100);
DISPLAY BOTH (-11400 4100);
FORCEPROP 1 LAST VALUE 1KOHM
J 0
(-11750 4100);
DISPLAY 1.212766 (-11750 4100);
PAINT GREEN (-11750 4100);
FORCEPROP 1 LAST PATH I441
R 1
J 0
(-12105 3903);
DISPLAY 1.212766 (-12105 3903);
PAINT GREEN (-12105 3903);
DISPLAY INVISIBLE (-12105 3903);
FORCEPROP 2 LAST CDS_LIB passive
J 0
(-12000 4100);
DISPLAY INVISIBLE (-12000 4100);
FORCEPROP 1 LAST CDS_LMAN_SYM_OUTLINE -50,50,50,-100
R 1
J 0
(-12000 4100);
DISPLAY 0.468085 (-12000 4100);
PAINT GREEN (-12000 4100);
DISPLAY INVISIBLE (-12000 4100);
FORCEPROP 1 LAST TOLERANCE 1%
R 1
J 0
(-12255 3903);
DISPLAY 1.212766 (-12255 3903);
PAINT GREEN (-12255 3903);
DISPLAY INVISIBLE (-12255 3903);
FORCEPROP 1 LAST CLS_PN G155-11001-01
R 1
J 0
(-12200 3964);
DISPLAY 1.212766 (-12200 3964);
PAINT GREEN (-12200 3964);
DISPLAY INVISIBLE (-12200 3964);
FORCEADD RESISTOR..2
R 1
(-12000 3900);
FORCEPROP 1 LAST $LOCATION R453
J 0
(-12350 3900);
DISPLAY 1.212766 (-12350 3900);
PAINT GREEN (-12350 3900);
FORCEPROP 0 LAST CDS_LOCATION R453
R 1
J 0
(-11750 4000);
DISPLAY 1.021277 (-11750 4000);
DISPLAY INVISIBLE (-11750 4000);
FORCEPROP 0 LAST $SEC 1
R 1
J 0
(-11750 4000);
DISPLAY 0.680851 (-11750 4000);
PAINT MONO (-11750 4000);
DISPLAY INVISIBLE (-11750 4000);
FORCEPROP 0 LAST CDS_SEC 1
R 1
J 0
(-11750 4000);
DISPLAY 1.021277 (-11750 4000);
DISPLAY INVISIBLE (-11750 4000);
FORCEPROP 0 LASTPIN (-12100 3900) $PN 1
J 2
(-12110 3910);
DISPLAY 0.680851 (-12110 3910);
PAINT MONO (-12110 3910);
FORCEPROP 0 LASTPIN (-11850 3900) $PN 2
J 0
(-11840 3910);
DISPLAY 0.680851 (-11840 3910);
PAINT MONO (-11840 3910);
FORCEPROP 0 LAST PACKAGE 0402
J 0
(-12050 3950);
DISPLAY 0.808511 (-12050 3950);
FORCEPROP 1 LAST VALUE 1KOHM
J 0
(-11750 3900);
DISPLAY 1.212766 (-11750 3900);
PAINT GREEN (-11750 3900);
FORCEPROP 0 LAST NO_ASSY TRUE
J 0
(-11400 3900);
DISPLAY 0.808511 (-11400 3900);
DISPLAY BOTH (-11400 3900);
FORCEPROP 1 LAST PATH I442
R 1
J 0
(-12105 3703);
DISPLAY 1.212766 (-12105 3703);
PAINT GREEN (-12105 3703);
DISPLAY INVISIBLE (-12105 3703);
FORCEPROP 2 LAST CDS_LIB passive
J 0
(-12000 3900);
DISPLAY INVISIBLE (-12000 3900);
FORCEPROP 1 LAST CDS_LMAN_SYM_OUTLINE -50,50,50,-100
R 1
J 0
(-12000 3900);
DISPLAY 0.468085 (-12000 3900);
PAINT GREEN (-12000 3900);
DISPLAY INVISIBLE (-12000 3900);
FORCEPROP 1 LAST TOLERANCE 1%
R 1
J 0
(-12255 3703);
DISPLAY 1.212766 (-12255 3703);
PAINT GREEN (-12255 3703);
DISPLAY INVISIBLE (-12255 3703);
FORCEPROP 1 LAST CLS_PN G155-11001-01
R 1
J 0
(-12200 3764);
DISPLAY 1.212766 (-12200 3764);
PAINT GREEN (-12200 3764);
DISPLAY INVISIBLE (-12200 3764);
FORCEADD RESISTOR..2
R 1
(-12000 4000);
FORCEPROP 1 LAST $LOCATION R452
J 0
(-12350 4000);
DISPLAY 1.212766 (-12350 4000);
PAINT GREEN (-12350 4000);
FORCEPROP 0 LAST CDS_LOCATION R452
R 1
J 0
(-11750 4100);
DISPLAY 1.021277 (-11750 4100);
DISPLAY INVISIBLE (-11750 4100);
FORCEPROP 0 LAST $SEC 1
R 1
J 0
(-11750 4100);
DISPLAY 0.680851 (-11750 4100);
PAINT MONO (-11750 4100);
DISPLAY INVISIBLE (-11750 4100);
FORCEPROP 0 LAST CDS_SEC 1
R 1
J 0
(-11750 4100);
DISPLAY 1.021277 (-11750 4100);
DISPLAY INVISIBLE (-11750 4100);
FORCEPROP 0 LASTPIN (-12100 4000) $PN 1
J 2
(-12110 4010);
DISPLAY 0.680851 (-12110 4010);
PAINT MONO (-12110 4010);
FORCEPROP 0 LASTPIN (-11850 4000) $PN 2
J 0
(-11840 4010);
DISPLAY 0.680851 (-11840 4010);
PAINT MONO (-11840 4010);
FORCEPROP 1 LAST VALUE 4.7KOHM
J 0
(-11750 4000);
DISPLAY 1.212766 (-11750 4000);
PAINT GREEN (-11750 4000);
FORCEPROP 0 LAST PACKAGE 0402
J 0
(-12050 4050);
DISPLAY 0.808511 (-12050 4050);
FORCEPROP 1 LAST PATH I443
R 1
J 0
(-12105 3803);
DISPLAY 1.212766 (-12105 3803);
PAINT GREEN (-12105 3803);
DISPLAY INVISIBLE (-12105 3803);
FORCEPROP 1 LAST TOLERANCE 1%
R 1
J 0
(-12255 3803);
DISPLAY 1.212766 (-12255 3803);
PAINT GREEN (-12255 3803);
DISPLAY INVISIBLE (-12255 3803);
FORCEPROP 1 LAST CLS_PN G155-14701-01
R 1
J 0
(-12200 3864);
DISPLAY 1.212766 (-12200 3864);
PAINT GREEN (-12200 3864);
DISPLAY INVISIBLE (-12200 3864);
FORCEPROP 1 LAST CDS_LMAN_SYM_OUTLINE -50,50,50,-100
R 1
J 0
(-12000 4000);
DISPLAY 0.468085 (-12000 4000);
PAINT GREEN (-12000 4000);
DISPLAY INVISIBLE (-12000 4000);
FORCEPROP 2 LAST CDS_LIB passive
J 0
(-12000 4000);
DISPLAY INVISIBLE (-12000 4000);
FORCEADD GND_SG..1
(-12700 3750);
FORCEPROP 3 LASTPIN (-12650 3800) SIG_NAME SG\g
J 0
(-12640 3810);
DISPLAY 0.659574 (-12640 3810);
PAINT MONO (-12640 3810);
DISPLAY INVISIBLE (-12640 3810);
FORCEPROP 1 LAST HDL_POWER SG
J 1
(-12645 3655);
DISPLAY 0.808511 (-12645 3655);
PAINT GREEN (-12645 3655);
FORCEPROP 0 LAST VOLTAGE 0
J 0
(-12600 3750);
DISPLAY 1.021277 (-12600 3750);
FORCEPROP 1 LAST BODY_TYPE PLUMBING
J 0
(-12685 3735);
DISPLAY 0.808511 (-12685 3735);
PAINT GREEN (-12685 3735);
DISPLAY INVISIBLE (-12685 3735);
FORCEPROP 1 LAST CDS_LMAN_SYM_OUTLINE 0,0,100,-50
J 0
(-12700 3750);
DISPLAY 0.468085 (-12700 3750);
PAINT GREEN (-12700 3750);
DISPLAY INVISIBLE (-12700 3750);
FORCEPROP 2 LAST CDS_LIB cls
J 0
(-12700 3750);
DISPLAY INVISIBLE (-12700 3750);
FORCEPROP 1 LAST PATH I444
J 0
(-12665 3750);
DISPLAY 0.808511 (-12665 3750);
PAINT GREEN (-12665 3750);
DISPLAY INVISIBLE (-12665 3750);
FORCEADD POWERMOS_3P_NCH_V1..1
(-13000 4100);
FORCEPROP 1 LAST $LOCATION Q1
J 0
(-12950 3700);
DISPLAY 1.212766 (-12950 3700);
PAINT GREEN (-12950 3700);
FORCEPROP 0 LAST CDS_LOCATION Q1
J 0
(-13550 3900);
DISPLAY 1.021277 (-13550 3900);
DISPLAY INVISIBLE (-13550 3900);
FORCEPROP 0 LAST $SEC 1
J 0
(-13550 3900);
DISPLAY 0.680851 (-13550 3900);
PAINT MONO (-13550 3900);
DISPLAY INVISIBLE (-13550 3900);
FORCEPROP 0 LAST CDS_SEC 1
J 0
(-13550 3900);
DISPLAY 1.021277 (-13550 3900);
DISPLAY INVISIBLE (-13550 3900);
FORCEPROP 0 LASTPIN (-12750 4300) $PN 3
J 0
(-12740 4310);
DISPLAY 0.680851 (-12740 4310);
PAINT MONO (-12740 4310);
FORCEPROP 0 LASTPIN (-13250 4000) $PN 1
J 2
(-13260 4010);
DISPLAY 0.680851 (-13260 4010);
PAINT MONO (-13260 4010);
FORCEPROP 0 LASTPIN (-12750 3900) $PN 2
J 0
(-12740 3910);
DISPLAY 0.680851 (-12740 3910);
PAINT MONO (-12740 3910);
FORCEPROP 1 LAST CLS_PN G121-10200-01
J 0
(-13550 3800);
DISPLAY 1.212766 (-13550 3800);
PAINT GREEN (-13550 3800);
FORCEPROP 0 LAST PART_NUMBER BSS138
J 0
(-13500 3700);
DISPLAY 1.021277 (-13500 3700);
FORCEPROP 1 LAST CDS_LMAN_SYM_OUTLINE -200,200,200,-200
J 0
(-13000 4100);
DISPLAY 0.468085 (-13000 4100);
PAINT GREEN (-13000 4100);
DISPLAY INVISIBLE (-13000 4100);
FORCEPROP 2 LAST CDS_LIB discrete
J 0
(-13000 4100);
DISPLAY INVISIBLE (-13000 4100);
FORCEPROP 1 LAST PATH I445
J 0
(-13359 4534);
DISPLAY 1.212766 (-13359 4534);
PAINT GREEN (-13359 4534);
DISPLAY INVISIBLE (-13359 4534);
FORCEPROP 2 LASTPIN (-12750 4300) SIG_NAME UN$524$POWERMOS3PNCHV1$I445$D
J 0
(-12740 4310);
DISPLAY 0.659574 (-12740 4310);
PAINT MONO (-12740 4310);
DISPLAY INVISIBLE (-12740 4310);
FORCEADD RESISTOR..1
(-13200 3450);
FORCEPROP 1 LAST $LOCATION R443
J 2
(-13400 3450);
DISPLAY 1.212766 (-13400 3450);
PAINT GREEN (-13400 3450);
FORCEPROP 0 LAST CDS_LOCATION R443
J 0
(-12950 3550);
DISPLAY 1.021277 (-12950 3550);
DISPLAY INVISIBLE (-12950 3550);
FORCEPROP 0 LAST $SEC 1
J 0
(-12950 3550);
DISPLAY 0.680851 (-12950 3550);
PAINT MONO (-12950 3550);
DISPLAY INVISIBLE (-12950 3550);
FORCEPROP 0 LAST CDS_SEC 1
J 0
(-12950 3550);
DISPLAY 1.021277 (-12950 3550);
DISPLAY INVISIBLE (-12950 3550);
FORCEPROP 0 LASTPIN (-13300 3450) $PN 1
J 2
(-13310 3460);
DISPLAY 0.680851 (-13310 3460);
PAINT MONO (-13310 3460);
FORCEPROP 0 LASTPIN (-13050 3450) $PN 2
J 0
(-13040 3460);
DISPLAY 0.680851 (-13040 3460);
PAINT MONO (-13040 3460);
FORCEPROP 1 LAST VALUE 100OHM
J 0
(-12950 3450);
DISPLAY 1.212766 (-12950 3450);
PAINT GREEN (-12950 3450);
FORCEPROP 0 LAST PACKAGE 0402
J 0
(-13250 3500);
DISPLAY 0.808511 (-13250 3500);
FORCEPROP 0 LAST NO_ASSY TRUE
J 0
(-13350 3350);
DISPLAY 0.808511 (-13350 3350);
DISPLAY BOTH (-13350 3350);
FORCEPROP 1 LAST PATH I446
J 0
(-13397 3555);
DISPLAY 1.212766 (-13397 3555);
PAINT GREEN (-13397 3555);
DISPLAY INVISIBLE (-13397 3555);
FORCEPROP 2 LAST CDS_LIB passive
J 0
(-13200 3450);
DISPLAY INVISIBLE (-13200 3450);
FORCEPROP 1 LAST CDS_LMAN_SYM_OUTLINE -50,50,100,-50
J 0
(-13200 3450);
DISPLAY 0.468085 (-13200 3450);
PAINT GREEN (-13200 3450);
DISPLAY INVISIBLE (-13200 3450);
FORCEPROP 1 LAST CLS_PN G155-11000-01
J 0
(-13336 3650);
DISPLAY 1.212766 (-13336 3650);
PAINT GREEN (-13336 3650);
DISPLAY INVISIBLE (-13336 3650);
FORCEPROP 1 LAST TOLERANCE 1%
J 0
(-13397 3705);
DISPLAY 1.212766 (-13397 3705);
PAINT GREEN (-13397 3705);
DISPLAY INVISIBLE (-13397 3705);
FORCEADD OFFPAGE_IN..2
R 2
(-14450 4000);
FORCEPROP 2 LAST $XR0 24E5> 
J 0
(-14633 4000);
DISPLAY 0.638298 (-14633 4000);
PAINT MONO (-14633 4000);
FORCEPROP 2 LAST $XR1 25C6<> 
J 0
(-14843 4000);
DISPLAY 0.638298 (-14843 4000);
PAINT MONO (-14843 4000);
FORCEPROP 1 LAST BODY_TYPE COMMENT
J 2
(-14460 4135);
DISPLAY 0.808511 (-14460 4135);
PAINT GREEN (-14460 4135);
DISPLAY INVISIBLE (-14460 4135);
FORCEPROP 1 LAST OFFPAGE TRUE
J 2
(-14460 4055);
DISPLAY 0.808511 (-14460 4055);
PAINT GREEN (-14460 4055);
DISPLAY INVISIBLE (-14460 4055);
FORCEPROP 1 LAST CDS_LMAN_SYM_OUTLINE -50,50,50,-50
J 2
(-14450 4000);
DISPLAY 0.468085 (-14450 4000);
PAINT GREEN (-14450 4000);
DISPLAY INVISIBLE (-14450 4000);
FORCEPROP 2 LAST CDS_LIB cls
J 0
(-14450 4000);
DISPLAY INVISIBLE (-14450 4000);
FORCEPROP 2 LAST PATH I447
J 0
(-14600 4050);
DISPLAY 1.021277 (-14600 4050);
DISPLAY INVISIBLE (-14600 4050);
FORCEADD TS3A5018PWR_TSSOP16..1
(-2100 5700);
FORCEPROP 1 LAST $LOCATION U37
J 0
(-2100 5750);
DISPLAY 1.212766 (-2100 5750);
PAINT GREEN (-2100 5750);
FORCEPROP 0 LAST CDS_LOCATION U37
J 0
(-1900 5900);
DISPLAY 1.021277 (-1900 5900);
DISPLAY INVISIBLE (-1900 5900);
FORCEPROP 0 LAST $SEC 1
J 0
(-1900 5900);
DISPLAY 0.680851 (-1900 5900);
PAINT MONO (-1900 5900);
DISPLAY INVISIBLE (-1900 5900);
FORCEPROP 0 LAST CDS_SEC 1
J 0
(-1900 5900);
DISPLAY 1.021277 (-1900 5900);
DISPLAY INVISIBLE (-1900 5900);
FORCEPROP 0 LASTPIN (-1400 5600) $PN 4
J 0
(-1390 5610);
DISPLAY 0.680851 (-1390 5610);
PAINT MONO (-1390 5610);
FORCEPROP 0 LASTPIN (-1400 5300) $PN 7
J 0
(-1390 5310);
DISPLAY 0.680851 (-1390 5310);
PAINT MONO (-1390 5310);
FORCEPROP 0 LASTPIN (-1400 5000) $PN 9
J 0
(-1390 5010);
DISPLAY 0.680851 (-1390 5010);
PAINT MONO (-1390 5010);
FORCEPROP 0 LASTPIN (-1400 4700) $PN 12
J 0
(-1390 4710);
DISPLAY 0.680851 (-1390 4710);
PAINT MONO (-1390 4710);
FORCEPROP 0 LASTPIN (-2200 4300) $PN 15
J 2
(-2210 4310);
DISPLAY 0.680851 (-2210 4310);
PAINT MONO (-2210 4310);
FORCEPROP 0 LASTPIN (-2200 4400) $PN 1
J 2
(-2210 4410);
DISPLAY 0.680851 (-2210 4410);
PAINT MONO (-2210 4410);
FORCEPROP 0 LASTPIN (-2200 5600) $PN 2
J 2
(-2210 5610);
DISPLAY 0.680851 (-2210 5610);
PAINT MONO (-2210 5610);
FORCEPROP 0 LASTPIN (-2200 5300) $PN 5
J 2
(-2210 5310);
DISPLAY 0.680851 (-2210 5310);
PAINT MONO (-2210 5310);
FORCEPROP 0 LASTPIN (-2200 5000) $PN 11
J 2
(-2210 5010);
DISPLAY 0.680851 (-2210 5010);
PAINT MONO (-2210 5010);
FORCEPROP 0 LASTPIN (-2200 4700) $PN 14
J 2
(-2210 4710);
DISPLAY 0.680851 (-2210 4710);
PAINT MONO (-2210 4710);
FORCEPROP 0 LASTPIN (-2200 5500) $PN 3
J 2
(-2210 5510);
DISPLAY 0.680851 (-2210 5510);
PAINT MONO (-2210 5510);
FORCEPROP 0 LASTPIN (-2200 5200) $PN 6
J 2
(-2210 5210);
DISPLAY 0.680851 (-2210 5210);
PAINT MONO (-2210 5210);
FORCEPROP 0 LASTPIN (-2200 4900) $PN 10
J 2
(-2210 4910);
DISPLAY 0.680851 (-2210 4910);
PAINT MONO (-2210 4910);
FORCEPROP 0 LASTPIN (-2200 4600) $PN 13
J 2
(-2210 4610);
DISPLAY 0.680851 (-2210 4610);
PAINT MONO (-2210 4610);
FORCEPROP 1 LAST CLS_PN G220-10324-01
J 0
(-1900 5750);
DISPLAY 1.212766 (-1900 5750);
PAINT GREEN (-1900 5750);
FORCEPROP 0 LAST PART_NUMBER TS3A5018PWR
J 0
(-1900 5850);
DISPLAY 1.021277 (-1900 5850);
FORCEPROP 2 LAST CDS_LIB stdlogic
J 0
(-2100 5700);
DISPLAY INVISIBLE (-2100 5700);
FORCEPROP 1 LAST CDS_LMAN_SYM_OUTLINE 0,0,600,-1500
J 0
(-2100 5700);
DISPLAY 0.468085 (-2100 5700);
PAINT GREEN (-2100 5700);
DISPLAY INVISIBLE (-2100 5700);
FORCEPROP 1 LAST PATH I448
J 0
(-2050 5750);
DISPLAY 1.212766 (-2050 5750);
PAINT GREEN (-2050 5750);
DISPLAY INVISIBLE (-2050 5750);
FORCEADD OFFPAGE_BI..1
(-300 5600);
FORCEPROP 2 LAST $XR0 16C4<> 
J 0
(-240 5600);
DISPLAY 0.638298 (-240 5600);
PAINT MONO (-240 5600);
FORCEPROP 1 LAST CDS_LMAN_SYM_OUTLINE -50,50,50,-50
J 0
(-300 5600);
DISPLAY 0.468085 (-300 5600);
PAINT GREEN (-300 5600);
DISPLAY INVISIBLE (-300 5600);
FORCEPROP 2 LAST CDS_LIB cls
J 0
(-300 5600);
DISPLAY INVISIBLE (-300 5600);
FORCEPROP 1 LAST BODY_TYPE COMMENT
J 0
(-290 5735);
DISPLAY 0.808511 (-290 5735);
PAINT GREEN (-290 5735);
DISPLAY INVISIBLE (-290 5735);
FORCEPROP 1 LAST OFFPAGE TRUE
J 0
(-290 5655);
DISPLAY 0.808511 (-290 5655);
PAINT GREEN (-290 5655);
DISPLAY INVISIBLE (-290 5655);
FORCEPROP 2 LAST PATH I449
J 0
(-200 5650);
DISPLAY 1.021277 (-200 5650);
DISPLAY INVISIBLE (-200 5650);
FORCEADD OFFPAGE_OUT..1
(-300 5300);
FORCEPROP 2 LAST $XR0 16D4< 
J 0
(-245 5300);
DISPLAY 0.638298 (-245 5300);
PAINT MONO (-245 5300);
FORCEPROP 1 LAST OFFPAGE TRUE
J 0
(-290 5355);
DISPLAY 0.808511 (-290 5355);
PAINT GREEN (-290 5355);
DISPLAY INVISIBLE (-290 5355);
FORCEPROP 2 LAST CDS_LIB cls
J 0
(-300 5300);
DISPLAY INVISIBLE (-300 5300);
FORCEPROP 1 LAST CDS_LMAN_SYM_OUTLINE -50,50,50,-50
J 0
(-300 5300);
DISPLAY 0.468085 (-300 5300);
PAINT GREEN (-300 5300);
DISPLAY INVISIBLE (-300 5300);
FORCEPROP 1 LAST BODY_TYPE COMMENT
J 0
(-290 5435);
DISPLAY 0.808511 (-290 5435);
PAINT GREEN (-290 5435);
DISPLAY INVISIBLE (-290 5435);
FORCEPROP 2 LAST PATH I450
J 0
(-200 5350);
DISPLAY 1.021277 (-200 5350);
DISPLAY INVISIBLE (-200 5350);
FORCEADD OFFPAGE_BI..1
(-300 5000);
FORCEPROP 2 LAST $XR0 16H3<> 
J 0
(-240 5000);
DISPLAY 0.638298 (-240 5000);
PAINT MONO (-240 5000);
FORCEPROP 1 LAST OFFPAGE TRUE
J 0
(-290 5055);
DISPLAY 0.808511 (-290 5055);
PAINT GREEN (-290 5055);
DISPLAY INVISIBLE (-290 5055);
FORCEPROP 1 LAST BODY_TYPE COMMENT
J 0
(-290 5135);
DISPLAY 0.808511 (-290 5135);
PAINT GREEN (-290 5135);
DISPLAY INVISIBLE (-290 5135);
FORCEPROP 2 LAST CDS_LIB cls
J 0
(-300 5000);
DISPLAY INVISIBLE (-300 5000);
FORCEPROP 1 LAST CDS_LMAN_SYM_OUTLINE -50,50,50,-50
J 0
(-300 5000);
DISPLAY 0.468085 (-300 5000);
PAINT GREEN (-300 5000);
DISPLAY INVISIBLE (-300 5000);
FORCEPROP 2 LAST PATH I451
J 0
(-200 5050);
DISPLAY 1.021277 (-200 5050);
DISPLAY INVISIBLE (-200 5050);
FORCEADD OFFPAGE_OUT..1
(-300 4700);
FORCEPROP 2 LAST $XR0 16H3< 
J 0
(-245 4700);
DISPLAY 0.638298 (-245 4700);
PAINT MONO (-245 4700);
FORCEPROP 1 LAST BODY_TYPE COMMENT
J 0
(-290 4835);
DISPLAY 0.808511 (-290 4835);
PAINT GREEN (-290 4835);
DISPLAY INVISIBLE (-290 4835);
FORCEPROP 1 LAST CDS_LMAN_SYM_OUTLINE -50,50,50,-50
J 0
(-300 4700);
DISPLAY 0.468085 (-300 4700);
PAINT GREEN (-300 4700);
DISPLAY INVISIBLE (-300 4700);
FORCEPROP 2 LAST CDS_LIB cls
J 0
(-300 4700);
DISPLAY INVISIBLE (-300 4700);
FORCEPROP 1 LAST OFFPAGE TRUE
J 0
(-290 4755);
DISPLAY 0.808511 (-290 4755);
PAINT GREEN (-290 4755);
DISPLAY INVISIBLE (-290 4755);
FORCEPROP 2 LAST PATH I452
J 0
(-200 4750);
DISPLAY 1.021277 (-200 4750);
DISPLAY INVISIBLE (-200 4750);
FORCEADD OFFPAGE_BI..1
R 2
(-3550 5600);
FORCEPROP 2 LAST $XR0 11G5<> 
J 0
(-3769 5600);
DISPLAY 0.638298 (-3769 5600);
PAINT MONO (-3769 5600);
FORCEPROP 2 LAST CDS_LIB cls
J 0
(-3550 5600);
DISPLAY INVISIBLE (-3550 5600);
FORCEPROP 1 LAST CDS_LMAN_SYM_OUTLINE -50,50,50,-50
J 2
(-3550 5600);
DISPLAY 0.468085 (-3550 5600);
PAINT GREEN (-3550 5600);
DISPLAY INVISIBLE (-3550 5600);
FORCEPROP 1 LAST BODY_TYPE COMMENT
J 2
(-3560 5735);
DISPLAY 0.808511 (-3560 5735);
PAINT GREEN (-3560 5735);
DISPLAY INVISIBLE (-3560 5735);
FORCEPROP 1 LAST OFFPAGE TRUE
J 2
(-3560 5655);
DISPLAY 0.808511 (-3560 5655);
PAINT GREEN (-3560 5655);
DISPLAY INVISIBLE (-3560 5655);
FORCEPROP 2 LAST PATH I453
J 0
(-3750 5650);
DISPLAY 1.021277 (-3750 5650);
DISPLAY INVISIBLE (-3750 5650);
FORCEADD OFFPAGE_BI..1
R 2
(-3550 5500);
FORCEPROP 2 LAST $XR0 24C13<> 
J 0
(-3800 5500);
DISPLAY 0.638298 (-3800 5500);
PAINT MONO (-3800 5500);
FORCEPROP 1 LAST BODY_TYPE COMMENT
J 2
(-3560 5635);
DISPLAY 0.808511 (-3560 5635);
PAINT GREEN (-3560 5635);
DISPLAY INVISIBLE (-3560 5635);
FORCEPROP 2 LAST CDS_LIB cls
J 0
(-3550 5500);
DISPLAY INVISIBLE (-3550 5500);
FORCEPROP 1 LAST CDS_LMAN_SYM_OUTLINE -50,50,50,-50
J 2
(-3550 5500);
DISPLAY 0.468085 (-3550 5500);
PAINT GREEN (-3550 5500);
DISPLAY INVISIBLE (-3550 5500);
FORCEPROP 1 LAST OFFPAGE TRUE
J 2
(-3560 5555);
DISPLAY 0.808511 (-3560 5555);
PAINT GREEN (-3560 5555);
DISPLAY INVISIBLE (-3560 5555);
FORCEPROP 2 LAST PATH I454
J 0
(-3800 5550);
DISPLAY 1.021277 (-3800 5550);
DISPLAY INVISIBLE (-3800 5550);
FORCEADD OFFPAGE_IN..2
R 2
(-3550 5200);
FORCEPROP 2 LAST $XR0 24C13> 
J 0
(-3764 5200);
DISPLAY 0.638298 (-3764 5200);
PAINT MONO (-3764 5200);
FORCEPROP 1 LAST OFFPAGE TRUE
J 2
(-3560 5255);
DISPLAY 0.808511 (-3560 5255);
PAINT GREEN (-3560 5255);
DISPLAY INVISIBLE (-3560 5255);
FORCEPROP 2 LAST CDS_LIB cls
J 0
(-3550 5200);
DISPLAY INVISIBLE (-3550 5200);
FORCEPROP 1 LAST CDS_LMAN_SYM_OUTLINE -50,50,50,-50
J 2
(-3550 5200);
DISPLAY 0.468085 (-3550 5200);
PAINT GREEN (-3550 5200);
DISPLAY INVISIBLE (-3550 5200);
FORCEPROP 1 LAST BODY_TYPE COMMENT
J 2
(-3560 5335);
DISPLAY 0.808511 (-3560 5335);
PAINT GREEN (-3560 5335);
DISPLAY INVISIBLE (-3560 5335);
FORCEPROP 2 LAST PATH I455
J 0
(-3750 5250);
DISPLAY 1.021277 (-3750 5250);
DISPLAY INVISIBLE (-3750 5250);
FORCEADD OFFPAGE_IN..2
R 2
(-3550 5300);
FORCEPROP 2 LAST $XR0 11H12<> 
J 0
(-3795 5300);
DISPLAY 0.638298 (-3795 5300);
PAINT MONO (-3795 5300);
FORCEPROP 2 LAST CDS_LIB cls
J 0
(-3550 5300);
DISPLAY INVISIBLE (-3550 5300);
FORCEPROP 1 LAST CDS_LMAN_SYM_OUTLINE -50,50,50,-50
J 2
(-3550 5300);
DISPLAY 0.468085 (-3550 5300);
PAINT GREEN (-3550 5300);
DISPLAY INVISIBLE (-3550 5300);
FORCEPROP 1 LAST BODY_TYPE COMMENT
J 2
(-3560 5435);
DISPLAY 0.808511 (-3560 5435);
PAINT GREEN (-3560 5435);
DISPLAY INVISIBLE (-3560 5435);
FORCEPROP 1 LAST OFFPAGE TRUE
J 2
(-3560 5355);
DISPLAY 0.808511 (-3560 5355);
PAINT GREEN (-3560 5355);
DISPLAY INVISIBLE (-3560 5355);
FORCEPROP 2 LAST PATH I456
J 0
(-3750 5350);
DISPLAY 1.021277 (-3750 5350);
DISPLAY INVISIBLE (-3750 5350);
FORCEADD OFFPAGE_BI..1
R 2
(-3550 5000);
FORCEPROP 2 LAST $XR0 11D5<> 
J 0
(-3769 5000);
DISPLAY 0.638298 (-3769 5000);
PAINT MONO (-3769 5000);
FORCEPROP 1 LAST BODY_TYPE COMMENT
J 2
(-3560 5135);
DISPLAY 0.808511 (-3560 5135);
PAINT GREEN (-3560 5135);
DISPLAY INVISIBLE (-3560 5135);
FORCEPROP 1 LAST OFFPAGE TRUE
J 2
(-3560 5055);
DISPLAY 0.808511 (-3560 5055);
PAINT GREEN (-3560 5055);
DISPLAY INVISIBLE (-3560 5055);
FORCEPROP 2 LAST PATH I457
J 0
(-3750 5050);
DISPLAY 1.021277 (-3750 5050);
DISPLAY INVISIBLE (-3750 5050);
FORCEPROP 1 LAST CDS_LMAN_SYM_OUTLINE -50,50,50,-50
J 2
(-3550 5000);
DISPLAY 0.468085 (-3550 5000);
PAINT GREEN (-3550 5000);
DISPLAY INVISIBLE (-3550 5000);
FORCEPROP 2 LAST CDS_LIB cls
J 0
(-3550 5000);
PAINT MONO (-3550 5000);
DISPLAY INVISIBLE (-3550 5000);
FORCEADD OFFPAGE_IN..2
R 2
(-3550 4700);
FORCEPROP 2 LAST $XR0 11D5<> 
J 0
(-3764 4700);
DISPLAY 0.638298 (-3764 4700);
PAINT MONO (-3764 4700);
FORCEPROP 2 LAST CDS_LIB cls
J 0
(-3550 4700);
DISPLAY INVISIBLE (-3550 4700);
FORCEPROP 1 LAST CDS_LMAN_SYM_OUTLINE -50,50,50,-50
J 2
(-3550 4700);
DISPLAY 0.468085 (-3550 4700);
PAINT GREEN (-3550 4700);
DISPLAY INVISIBLE (-3550 4700);
FORCEPROP 1 LAST BODY_TYPE COMMENT
J 2
(-3560 4835);
DISPLAY 0.808511 (-3560 4835);
PAINT GREEN (-3560 4835);
DISPLAY INVISIBLE (-3560 4835);
FORCEPROP 1 LAST OFFPAGE TRUE
J 2
(-3560 4755);
DISPLAY 0.808511 (-3560 4755);
PAINT GREEN (-3560 4755);
DISPLAY INVISIBLE (-3560 4755);
FORCEPROP 2 LAST PATH I458
J 0
(-3750 4750);
DISPLAY 1.021277 (-3750 4750);
DISPLAY INVISIBLE (-3750 4750);
FORCEADD RESISTOR..1
(-3000 4400);
FORCEPROP 1 LAST $LOCATION R485
J 2
(-3200 4400);
DISPLAY 1.212766 (-3200 4400);
PAINT GREEN (-3200 4400);
FORCEPROP 0 LAST CDS_LOCATION R485
J 0
(-2800 4500);
DISPLAY 1.021277 (-2800 4500);
DISPLAY INVISIBLE (-2800 4500);
FORCEPROP 0 LAST $SEC 1
J 0
(-2800 4500);
DISPLAY 0.680851 (-2800 4500);
PAINT MONO (-2800 4500);
DISPLAY INVISIBLE (-2800 4500);
FORCEPROP 0 LAST CDS_SEC 1
J 0
(-2800 4500);
DISPLAY 1.021277 (-2800 4500);
DISPLAY INVISIBLE (-2800 4500);
FORCEPROP 0 LASTPIN (-3100 4400) $PN 1
J 2
(-3110 4410);
DISPLAY 0.680851 (-3110 4410);
PAINT MONO (-3110 4410);
FORCEPROP 0 LASTPIN (-2850 4400) $PN 2
J 0
(-2840 4410);
DISPLAY 0.680851 (-2840 4410);
PAINT MONO (-2840 4410);
FORCEPROP 0 LAST PACKAGE 0402
J 0
(-3050 4350);
DISPLAY 0.808511 (-3050 4350);
FORCEPROP 0 LAST NO_ASSY TRUE
J 0
(-3200 4450);
DISPLAY 0.808511 (-3200 4450);
DISPLAY BOTH (-3200 4450);
FORCEPROP 1 LAST VALUE 33OHM
J 0
(-2800 4400);
DISPLAY 1.212766 (-2800 4400);
PAINT GREEN (-2800 4400);
FORCEPROP 1 LAST TOLERANCE 1%
J 0
(-3197 4655);
DISPLAY 1.212766 (-3197 4655);
PAINT GREEN (-3197 4655);
DISPLAY INVISIBLE (-3197 4655);
FORCEPROP 2 LAST CDS_LIB passive
J 0
(-3000 4400);
DISPLAY INVISIBLE (-3000 4400);
FORCEPROP 1 LAST CDS_LMAN_SYM_OUTLINE -50,50,100,-50
J 0
(-3000 4400);
DISPLAY 0.468085 (-3000 4400);
PAINT GREEN (-3000 4400);
DISPLAY INVISIBLE (-3000 4400);
FORCEPROP 1 LAST CLS_PN G155-133R0-01
J 0
(-3136 4600);
DISPLAY 1.212766 (-3136 4600);
PAINT GREEN (-3136 4600);
DISPLAY INVISIBLE (-3136 4600);
FORCEPROP 1 LAST PATH I459
J 0
(-3197 4505);
DISPLAY 1.212766 (-3197 4505);
PAINT GREEN (-3197 4505);
DISPLAY INVISIBLE (-3197 4505);
FORCEADD RESISTOR..1
(-3000 4300);
FORCEPROP 1 LAST $LOCATION R486
J 2
(-3200 4300);
DISPLAY 1.212766 (-3200 4300);
PAINT GREEN (-3200 4300);
FORCEPROP 0 LAST CDS_LOCATION R486
J 0
(-2800 4400);
DISPLAY 1.021277 (-2800 4400);
DISPLAY INVISIBLE (-2800 4400);
FORCEPROP 0 LAST $SEC 1
J 0
(-2800 4400);
DISPLAY 0.680851 (-2800 4400);
PAINT MONO (-2800 4400);
DISPLAY INVISIBLE (-2800 4400);
FORCEPROP 0 LAST CDS_SEC 1
J 0
(-2800 4400);
DISPLAY 1.021277 (-2800 4400);
DISPLAY INVISIBLE (-2800 4400);
FORCEPROP 0 LASTPIN (-3100 4300) $PN 1
J 2
(-3110 4310);
DISPLAY 0.680851 (-3110 4310);
PAINT MONO (-3110 4310);
FORCEPROP 0 LASTPIN (-2850 4300) $PN 2
J 0
(-2840 4310);
DISPLAY 0.680851 (-2840 4310);
PAINT MONO (-2840 4310);
FORCEPROP 0 LAST PACKAGE 0402
J 0
(-3050 4250);
DISPLAY 0.808511 (-3050 4250);
FORCEPROP 1 LAST VALUE 33OHM
J 0
(-2800 4300);
DISPLAY 1.212766 (-2800 4300);
PAINT GREEN (-2800 4300);
FORCEPROP 1 LAST CLS_PN G155-133R0-01
J 0
(-3136 4500);
DISPLAY 1.212766 (-3136 4500);
PAINT GREEN (-3136 4500);
DISPLAY INVISIBLE (-3136 4500);
FORCEPROP 1 LAST CDS_LMAN_SYM_OUTLINE -50,50,100,-50
J 0
(-3000 4300);
DISPLAY 0.468085 (-3000 4300);
PAINT GREEN (-3000 4300);
DISPLAY INVISIBLE (-3000 4300);
FORCEPROP 2 LAST CDS_LIB passive
J 0
(-3000 4300);
DISPLAY INVISIBLE (-3000 4300);
FORCEPROP 1 LAST TOLERANCE 1%
J 0
(-3197 4555);
DISPLAY 1.212766 (-3197 4555);
PAINT GREEN (-3197 4555);
DISPLAY INVISIBLE (-3197 4555);
FORCEPROP 1 LAST PATH I460
J 0
(-3197 4405);
DISPLAY 1.212766 (-3197 4405);
PAINT GREEN (-3197 4405);
DISPLAY INVISIBLE (-3197 4405);
FORCEADD VCC..1
(-3650 4000);
FORCEPROP 3 LASTPIN (-3600 3950) SIG_NAME XP3R3V_FPGA\g
J 0
(-3590 3960);
DISPLAY 0.659574 (-3590 3960);
PAINT MONO (-3590 3960);
DISPLAY INVISIBLE (-3590 3960);
FORCEPROP 0 LAST VOLTAGE 3.3V
J 0
(-3850 4100);
DISPLAY 1.021277 (-3850 4100);
DISPLAY BOTH (-3850 4100);
FORCEPROP 1 LAST HDL_POWER XP3R3V_FPGA
J 1
(-3595 4055);
DISPLAY 1.021277 (-3595 4055);
PAINT GREEN (-3595 4055);
FORCEPROP 1 LAST CDS_LMAN_SYM_OUTLINE -250,250,250,-250
J 0
(-3650 4000);
DISPLAY 0.468085 (-3650 4000);
PAINT GREEN (-3650 4000);
DISPLAY INVISIBLE (-3650 4000);
FORCEPROP 2 LAST CDS_LIB cls
J 0
(-3650 4000);
DISPLAY INVISIBLE (-3650 4000);
FORCEPROP 1 LAST BODY_TYPE PLUMBING
J 0
(-3695 3957);
DISPLAY 0.340426 (-3695 3957);
PAINT GREEN (-3695 3957);
DISPLAY INVISIBLE (-3695 3957);
FORCEPROP 1 LAST PATH I461
J 0
(-3615 4090);
DISPLAY 0.808511 (-3615 4090);
PAINT GREEN (-3615 4090);
DISPLAY INVISIBLE (-3615 4090);
FORCEADD RESISTOR..2
R 1
(-3150 3750);
FORCEPROP 1 LAST $LOCATION R483
J 0
(-3450 3750);
DISPLAY 1.212766 (-3450 3750);
PAINT GREEN (-3450 3750);
FORCEPROP 0 LAST CDS_LOCATION R483
R 1
J 0
(-2900 3850);
DISPLAY 1.021277 (-2900 3850);
DISPLAY INVISIBLE (-2900 3850);
FORCEPROP 0 LAST $SEC 1
R 1
J 0
(-2900 3850);
DISPLAY 0.680851 (-2900 3850);
PAINT MONO (-2900 3850);
DISPLAY INVISIBLE (-2900 3850);
FORCEPROP 0 LAST CDS_SEC 1
R 1
J 0
(-2900 3850);
DISPLAY 1.021277 (-2900 3850);
DISPLAY INVISIBLE (-2900 3850);
FORCEPROP 0 LASTPIN (-3250 3750) $PN 1
J 2
(-3260 3760);
DISPLAY 0.680851 (-3260 3760);
PAINT MONO (-3260 3760);
FORCEPROP 0 LASTPIN (-3000 3750) $PN 2
J 0
(-2990 3760);
DISPLAY 0.680851 (-2990 3760);
PAINT MONO (-2990 3760);
FORCEPROP 1 LAST VALUE 1KOHM
J 0
(-2900 3750);
DISPLAY 1.212766 (-2900 3750);
PAINT GREEN (-2900 3750);
FORCEPROP 0 LAST PACKAGE 0402
J 0
(-3200 3800);
DISPLAY 0.808511 (-3200 3800);
FORCEPROP 1 LAST CLS_PN G155-11001-01
R 1
J 0
(-3350 3614);
DISPLAY 1.212766 (-3350 3614);
PAINT GREEN (-3350 3614);
DISPLAY INVISIBLE (-3350 3614);
FORCEPROP 1 LAST TOLERANCE 1%
R 1
J 0
(-3405 3553);
DISPLAY 1.212766 (-3405 3553);
PAINT GREEN (-3405 3553);
DISPLAY INVISIBLE (-3405 3553);
FORCEPROP 1 LAST CDS_LMAN_SYM_OUTLINE -50,50,50,-100
R 1
J 0
(-3150 3750);
DISPLAY 0.468085 (-3150 3750);
PAINT GREEN (-3150 3750);
DISPLAY INVISIBLE (-3150 3750);
FORCEPROP 2 LAST CDS_LIB passive
J 0
(-3150 3750);
DISPLAY INVISIBLE (-3150 3750);
FORCEPROP 1 LAST PATH I462
R 1
J 0
(-3255 3553);
DISPLAY 1.212766 (-3255 3553);
PAINT GREEN (-3255 3553);
DISPLAY INVISIBLE (-3255 3553);
FORCEADD RESISTOR..2
R 1
(-3150 3650);
FORCEPROP 1 LAST $LOCATION R484
J 0
(-3450 3650);
DISPLAY 1.212766 (-3450 3650);
PAINT GREEN (-3450 3650);
FORCEPROP 0 LAST CDS_LOCATION R484
R 1
J 0
(-2900 3750);
DISPLAY 1.021277 (-2900 3750);
DISPLAY INVISIBLE (-2900 3750);
FORCEPROP 0 LAST $SEC 1
R 1
J 0
(-2900 3750);
DISPLAY 0.680851 (-2900 3750);
PAINT MONO (-2900 3750);
DISPLAY INVISIBLE (-2900 3750);
FORCEPROP 0 LAST CDS_SEC 1
R 1
J 0
(-2900 3750);
DISPLAY 1.021277 (-2900 3750);
DISPLAY INVISIBLE (-2900 3750);
FORCEPROP 0 LASTPIN (-3250 3650) $PN 1
J 2
(-3260 3660);
DISPLAY 0.680851 (-3260 3660);
PAINT MONO (-3260 3660);
FORCEPROP 0 LASTPIN (-3000 3650) $PN 2
J 0
(-2990 3660);
DISPLAY 0.680851 (-2990 3660);
PAINT MONO (-2990 3660);
FORCEPROP 1 LAST VALUE 1KOHM
J 0
(-2900 3650);
DISPLAY 1.212766 (-2900 3650);
PAINT GREEN (-2900 3650);
FORCEPROP 0 LAST PACKAGE 0402
J 0
(-3200 3700);
DISPLAY 0.808511 (-3200 3700);
FORCEPROP 2 LAST CDS_LIB passive
J 0
(-3150 3650);
DISPLAY INVISIBLE (-3150 3650);
FORCEPROP 1 LAST CDS_LMAN_SYM_OUTLINE -50,50,50,-100
R 1
J 0
(-3150 3650);
DISPLAY 0.468085 (-3150 3650);
PAINT GREEN (-3150 3650);
DISPLAY INVISIBLE (-3150 3650);
FORCEPROP 1 LAST TOLERANCE 1%
R 1
J 0
(-3405 3453);
DISPLAY 1.212766 (-3405 3453);
PAINT GREEN (-3405 3453);
DISPLAY INVISIBLE (-3405 3453);
FORCEPROP 1 LAST CLS_PN G155-11001-01
R 1
J 0
(-3350 3514);
DISPLAY 1.212766 (-3350 3514);
PAINT GREEN (-3350 3514);
DISPLAY INVISIBLE (-3350 3514);
FORCEPROP 1 LAST PATH I463
R 1
J 0
(-3255 3453);
DISPLAY 1.212766 (-3255 3453);
PAINT GREEN (-3255 3453);
DISPLAY INVISIBLE (-3255 3453);
FORCEPROP 2 LASTPIN (-3000 3650) SIG_NAME UN$524$RESISTOR$I463$2
J 0
(-2990 3660);
DISPLAY 0.659574 (-2990 3660);
PAINT MONO (-2990 3660);
DISPLAY INVISIBLE (-2990 3660);
FORCEADD RESISTOR..2
R 1
(-3150 3850);
FORCEPROP 1 LAST $LOCATION R482
J 0
(-3450 3850);
DISPLAY 1.212766 (-3450 3850);
PAINT GREEN (-3450 3850);
FORCEPROP 0 LAST CDS_LOCATION R482
R 1
J 0
(-2900 3950);
DISPLAY 1.021277 (-2900 3950);
DISPLAY INVISIBLE (-2900 3950);
FORCEPROP 0 LAST $SEC 1
R 1
J 0
(-2900 3950);
DISPLAY 0.680851 (-2900 3950);
PAINT MONO (-2900 3950);
DISPLAY INVISIBLE (-2900 3950);
FORCEPROP 0 LAST CDS_SEC 1
R 1
J 0
(-2900 3950);
DISPLAY 1.021277 (-2900 3950);
DISPLAY INVISIBLE (-2900 3950);
FORCEPROP 0 LASTPIN (-3250 3850) $PN 1
J 2
(-3260 3860);
DISPLAY 0.680851 (-3260 3860);
PAINT MONO (-3260 3860);
FORCEPROP 0 LASTPIN (-3000 3850) $PN 2
J 0
(-2990 3860);
DISPLAY 0.680851 (-2990 3860);
PAINT MONO (-2990 3860);
FORCEPROP 1 LAST VALUE 4.7KOHM
J 0
(-2900 3850);
DISPLAY 1.212766 (-2900 3850);
PAINT GREEN (-2900 3850);
FORCEPROP 0 LAST NO_ASSY TRUE
J 0
(-4200 3850);
DISPLAY 1.021277 (-4200 3850);
DISPLAY BOTH (-4200 3850);
FORCEPROP 0 LAST PACKAGE 0402
J 0
(-3200 3900);
DISPLAY 0.808511 (-3200 3900);
FORCEPROP 2 LAST CDS_LIB passive
J 0
(-3150 3850);
DISPLAY INVISIBLE (-3150 3850);
FORCEPROP 1 LAST CDS_LMAN_SYM_OUTLINE -50,50,50,-100
R 1
J 0
(-3150 3850);
DISPLAY 0.468085 (-3150 3850);
PAINT GREEN (-3150 3850);
DISPLAY INVISIBLE (-3150 3850);
FORCEPROP 1 LAST CLS_PN G155-14701-01
R 1
J 0
(-3350 3714);
DISPLAY 1.212766 (-3350 3714);
PAINT GREEN (-3350 3714);
DISPLAY INVISIBLE (-3350 3714);
FORCEPROP 1 LAST TOLERANCE 1%
R 1
J 0
(-3405 3653);
DISPLAY 1.212766 (-3405 3653);
PAINT GREEN (-3405 3653);
DISPLAY INVISIBLE (-3405 3653);
FORCEPROP 1 LAST PATH I464
R 1
J 0
(-3255 3653);
DISPLAY 1.212766 (-3255 3653);
PAINT GREEN (-3255 3653);
DISPLAY INVISIBLE (-3255 3653);
FORCEADD GND_SG..1
(-3650 3500);
FORCEPROP 3 LASTPIN (-3600 3550) SIG_NAME SG\g
J 0
(-3590 3560);
DISPLAY 0.659574 (-3590 3560);
PAINT MONO (-3590 3560);
DISPLAY INVISIBLE (-3590 3560);
FORCEPROP 1 LAST HDL_POWER SG
J 1
(-3595 3405);
DISPLAY 0.808511 (-3595 3405);
PAINT GREEN (-3595 3405);
FORCEPROP 0 LAST VOLTAGE 0
J 0
(-3550 3500);
DISPLAY 1.021277 (-3550 3500);
FORCEPROP 1 LAST BODY_TYPE PLUMBING
J 0
(-3635 3485);
DISPLAY 0.808511 (-3635 3485);
PAINT GREEN (-3635 3485);
DISPLAY INVISIBLE (-3635 3485);
FORCEPROP 2 LAST CDS_LIB cls
J 0
(-3650 3500);
DISPLAY INVISIBLE (-3650 3500);
FORCEPROP 1 LAST CDS_LMAN_SYM_OUTLINE 0,0,100,-50
J 0
(-3650 3500);
DISPLAY 0.468085 (-3650 3500);
PAINT GREEN (-3650 3500);
DISPLAY INVISIBLE (-3650 3500);
FORCEPROP 1 LAST PATH I465
J 0
(-3615 3500);
DISPLAY 0.808511 (-3615 3500);
PAINT GREEN (-3615 3500);
DISPLAY INVISIBLE (-3615 3500);
FORCEADD RESISTOR..2
R 1
(-4500 5550);
FORCEPROP 1 LAST $LOCATION R474
J 0
(-4900 5550);
DISPLAY 1.212766 (-4900 5550);
PAINT GREEN (-4900 5550);
FORCEPROP 0 LAST CDS_LOCATION R474
R 1
J 0
(-4550 5650);
DISPLAY 1.021277 (-4550 5650);
DISPLAY INVISIBLE (-4550 5650);
FORCEPROP 0 LAST $SEC 1
R 1
J 0
(-4550 5650);
DISPLAY 0.680851 (-4550 5650);
PAINT MONO (-4550 5650);
DISPLAY INVISIBLE (-4550 5650);
FORCEPROP 0 LAST CDS_SEC 1
R 1
J 0
(-4550 5650);
DISPLAY 1.021277 (-4550 5650);
DISPLAY INVISIBLE (-4550 5650);
FORCEPROP 0 LASTPIN (-4600 5550) $PN 1
J 2
(-4610 5560);
DISPLAY 0.680851 (-4610 5560);
PAINT MONO (-4610 5560);
FORCEPROP 0 LASTPIN (-4350 5550) $PN 2
J 0
(-4340 5560);
DISPLAY 0.680851 (-4340 5560);
PAINT MONO (-4340 5560);
FORCEPROP 0 LAST PACKAGE 0402
J 0
(-4550 5600);
DISPLAY 0.808511 (-4550 5600);
FORCEPROP 1 LAST VALUE 100KOHM
J 0
(-4300 5550);
DISPLAY 0.978723 (-4300 5550);
PAINT GREEN (-4300 5550);
FORCEPROP 1 LAST PATH I466
R 1
J 0
(-4605 5353);
DISPLAY 1.212766 (-4605 5353);
PAINT GREEN (-4605 5353);
DISPLAY INVISIBLE (-4605 5353);
FORCEPROP 1 LAST CLS_PN G155-11003-01
R 1
J 0
(-4700 5414);
DISPLAY 1.212766 (-4700 5414);
PAINT GREEN (-4700 5414);
DISPLAY INVISIBLE (-4700 5414);
FORCEPROP 1 LAST CDS_LMAN_SYM_OUTLINE -50,50,50,-100
R 1
J 0
(-4500 5550);
DISPLAY 0.468085 (-4500 5550);
PAINT GREEN (-4500 5550);
DISPLAY INVISIBLE (-4500 5550);
FORCEPROP 2 LAST CDS_LIB passive
J 0
(-4500 5550);
DISPLAY INVISIBLE (-4500 5550);
FORCEPROP 1 LAST TOLERANCE 1%
R 1
J 0
(-4755 5353);
DISPLAY 1.212766 (-4755 5353);
PAINT GREEN (-4755 5353);
DISPLAY INVISIBLE (-4755 5353);
FORCEADD RESISTOR..2
R 1
(-4500 5250);
FORCEPROP 1 LAST $LOCATION R475
J 0
(-4900 5250);
DISPLAY 1.212766 (-4900 5250);
PAINT GREEN (-4900 5250);
FORCEPROP 0 LAST CDS_LOCATION R475
R 1
J 0
(-4550 5350);
DISPLAY 1.021277 (-4550 5350);
DISPLAY INVISIBLE (-4550 5350);
FORCEPROP 0 LAST $SEC 1
R 1
J 0
(-4550 5350);
DISPLAY 0.680851 (-4550 5350);
PAINT MONO (-4550 5350);
DISPLAY INVISIBLE (-4550 5350);
FORCEPROP 0 LAST CDS_SEC 1
R 1
J 0
(-4550 5350);
DISPLAY 1.021277 (-4550 5350);
DISPLAY INVISIBLE (-4550 5350);
FORCEPROP 0 LASTPIN (-4600 5250) $PN 1
J 2
(-4610 5260);
DISPLAY 0.680851 (-4610 5260);
PAINT MONO (-4610 5260);
FORCEPROP 0 LASTPIN (-4350 5250) $PN 2
J 0
(-4340 5260);
DISPLAY 0.680851 (-4340 5260);
PAINT MONO (-4340 5260);
FORCEPROP 1 LAST VALUE 100KOHM
J 0
(-4300 5250);
DISPLAY 0.978723 (-4300 5250);
PAINT GREEN (-4300 5250);
FORCEPROP 0 LAST PACKAGE 0402
J 0
(-4550 5300);
DISPLAY 0.808511 (-4550 5300);
FORCEPROP 1 LAST PATH I467
R 1
J 0
(-4605 5053);
DISPLAY 1.212766 (-4605 5053);
PAINT GREEN (-4605 5053);
DISPLAY INVISIBLE (-4605 5053);
FORCEPROP 1 LAST TOLERANCE 1%
R 1
J 0
(-4755 5053);
DISPLAY 1.212766 (-4755 5053);
PAINT GREEN (-4755 5053);
DISPLAY INVISIBLE (-4755 5053);
FORCEPROP 2 LAST CDS_LIB passive
J 0
(-4500 5250);
DISPLAY INVISIBLE (-4500 5250);
FORCEPROP 1 LAST CDS_LMAN_SYM_OUTLINE -50,50,50,-100
R 1
J 0
(-4500 5250);
DISPLAY 0.468085 (-4500 5250);
PAINT GREEN (-4500 5250);
DISPLAY INVISIBLE (-4500 5250);
FORCEPROP 1 LAST CLS_PN G155-11003-01
R 1
J 0
(-4700 5114);
DISPLAY 1.212766 (-4700 5114);
PAINT GREEN (-4700 5114);
DISPLAY INVISIBLE (-4700 5114);
FORCEADD RESISTOR..2
R 1
(-4500 4950);
FORCEPROP 1 LAST $LOCATION R476
J 0
(-4900 4950);
DISPLAY 1.212766 (-4900 4950);
PAINT GREEN (-4900 4950);
FORCEPROP 0 LAST CDS_LOCATION R476
R 1
J 0
(-4550 5050);
DISPLAY 1.021277 (-4550 5050);
DISPLAY INVISIBLE (-4550 5050);
FORCEPROP 0 LAST $SEC 1
R 1
J 0
(-4550 5050);
DISPLAY 0.680851 (-4550 5050);
PAINT MONO (-4550 5050);
DISPLAY INVISIBLE (-4550 5050);
FORCEPROP 0 LAST CDS_SEC 1
R 1
J 0
(-4550 5050);
DISPLAY 1.021277 (-4550 5050);
DISPLAY INVISIBLE (-4550 5050);
FORCEPROP 0 LASTPIN (-4600 4950) $PN 1
J 2
(-4610 4960);
DISPLAY 0.680851 (-4610 4960);
PAINT MONO (-4610 4960);
FORCEPROP 0 LASTPIN (-4350 4950) $PN 2
J 0
(-4340 4960);
DISPLAY 0.680851 (-4340 4960);
PAINT MONO (-4340 4960);
FORCEPROP 0 LAST PACKAGE 0402
J 0
(-4550 5000);
DISPLAY 0.808511 (-4550 5000);
FORCEPROP 1 LAST VALUE 100KOHM
J 0
(-4300 4950);
DISPLAY 0.978723 (-4300 4950);
PAINT GREEN (-4300 4950);
FORCEPROP 1 LAST PATH I468
R 1
J 0
(-4605 4753);
DISPLAY 1.212766 (-4605 4753);
PAINT GREEN (-4605 4753);
DISPLAY INVISIBLE (-4605 4753);
FORCEPROP 1 LAST TOLERANCE 1%
R 1
J 0
(-4755 4753);
DISPLAY 1.212766 (-4755 4753);
PAINT GREEN (-4755 4753);
DISPLAY INVISIBLE (-4755 4753);
FORCEPROP 2 LAST CDS_LIB passive
J 0
(-4500 4950);
DISPLAY INVISIBLE (-4500 4950);
FORCEPROP 1 LAST CDS_LMAN_SYM_OUTLINE -50,50,50,-100
R 1
J 0
(-4500 4950);
DISPLAY 0.468085 (-4500 4950);
PAINT GREEN (-4500 4950);
DISPLAY INVISIBLE (-4500 4950);
FORCEPROP 1 LAST CLS_PN G155-11003-01
R 1
J 0
(-4700 4814);
DISPLAY 1.212766 (-4700 4814);
PAINT GREEN (-4700 4814);
DISPLAY INVISIBLE (-4700 4814);
FORCEADD RESISTOR..2
R 1
(-4500 4650);
FORCEPROP 1 LAST $LOCATION R477
J 0
(-4900 4650);
DISPLAY 1.212766 (-4900 4650);
PAINT GREEN (-4900 4650);
FORCEPROP 0 LAST CDS_LOCATION R477
R 1
J 0
(-4550 4750);
DISPLAY 1.021277 (-4550 4750);
DISPLAY INVISIBLE (-4550 4750);
FORCEPROP 0 LAST $SEC 1
R 1
J 0
(-4550 4750);
DISPLAY 0.680851 (-4550 4750);
PAINT MONO (-4550 4750);
DISPLAY INVISIBLE (-4550 4750);
FORCEPROP 0 LAST CDS_SEC 1
R 1
J 0
(-4550 4750);
DISPLAY 1.021277 (-4550 4750);
DISPLAY INVISIBLE (-4550 4750);
FORCEPROP 0 LASTPIN (-4600 4650) $PN 1
J 2
(-4610 4660);
DISPLAY 0.680851 (-4610 4660);
PAINT MONO (-4610 4660);
FORCEPROP 0 LASTPIN (-4350 4650) $PN 2
J 0
(-4340 4660);
DISPLAY 0.680851 (-4340 4660);
PAINT MONO (-4340 4660);
FORCEPROP 0 LAST PACKAGE 0402
J 0
(-4550 4700);
DISPLAY 0.808511 (-4550 4700);
FORCEPROP 1 LAST VALUE 100KOHM
J 0
(-4300 4650);
DISPLAY 0.978723 (-4300 4650);
PAINT GREEN (-4300 4650);
FORCEPROP 1 LAST PATH I469
R 1
J 0
(-4605 4453);
DISPLAY 1.212766 (-4605 4453);
PAINT GREEN (-4605 4453);
DISPLAY INVISIBLE (-4605 4453);
FORCEPROP 1 LAST CLS_PN G155-11003-01
R 1
J 0
(-4700 4514);
DISPLAY 1.212766 (-4700 4514);
PAINT GREEN (-4700 4514);
DISPLAY INVISIBLE (-4700 4514);
FORCEPROP 1 LAST CDS_LMAN_SYM_OUTLINE -50,50,50,-100
R 1
J 0
(-4500 4650);
DISPLAY 0.468085 (-4500 4650);
PAINT GREEN (-4500 4650);
DISPLAY INVISIBLE (-4500 4650);
FORCEPROP 2 LAST CDS_LIB passive
J 0
(-4500 4650);
DISPLAY INVISIBLE (-4500 4650);
FORCEPROP 1 LAST TOLERANCE 1%
R 1
J 0
(-4755 4453);
DISPLAY 1.212766 (-4755 4453);
PAINT GREEN (-4755 4453);
DISPLAY INVISIBLE (-4755 4453);
FORCEADD VCC..1
(-5000 5750);
FORCEPROP 3 LASTPIN (-4950 5700) SIG_NAME XP3R3V_FPGA\g
J 0
(-4940 5710);
DISPLAY 0.659574 (-4940 5710);
PAINT MONO (-4940 5710);
DISPLAY INVISIBLE (-4940 5710);
FORCEPROP 0 LAST VOLTAGE 3.3V
J 0
(-5200 5850);
DISPLAY 1.021277 (-5200 5850);
DISPLAY BOTH (-5200 5850);
FORCEPROP 1 LAST HDL_POWER XP3R3V_FPGA
J 1
(-4945 5805);
DISPLAY 1.021277 (-4945 5805);
PAINT GREEN (-4945 5805);
FORCEPROP 1 LAST BODY_TYPE PLUMBING
J 0
(-5045 5707);
DISPLAY 0.340426 (-5045 5707);
PAINT GREEN (-5045 5707);
DISPLAY INVISIBLE (-5045 5707);
FORCEPROP 1 LAST CDS_LMAN_SYM_OUTLINE -250,250,250,-250
J 0
(-5000 5750);
DISPLAY 0.468085 (-5000 5750);
PAINT GREEN (-5000 5750);
DISPLAY INVISIBLE (-5000 5750);
FORCEPROP 2 LAST CDS_LIB cls
J 0
(-5000 5750);
DISPLAY INVISIBLE (-5000 5750);
FORCEPROP 1 LAST PATH I470
J 0
(-4965 5840);
DISPLAY 0.808511 (-4965 5840);
PAINT GREEN (-4965 5840);
DISPLAY INVISIBLE (-4965 5840);
FORCEADD OFFPAGE_IN..2
R 2
(-4350 4400);
FORCEPROP 2 LAST $XR0 12D5> 
J 0
(-4533 4400);
DISPLAY 0.638298 (-4533 4400);
PAINT MONO (-4533 4400);
FORCEPROP 2 LAST CDS_LIB cls
J 0
(-4350 4400);
DISPLAY INVISIBLE (-4350 4400);
FORCEPROP 1 LAST CDS_LMAN_SYM_OUTLINE -50,50,50,-50
J 2
(-4350 4400);
DISPLAY 0.468085 (-4350 4400);
PAINT GREEN (-4350 4400);
DISPLAY INVISIBLE (-4350 4400);
FORCEPROP 1 LAST BODY_TYPE COMMENT
J 2
(-4360 4535);
DISPLAY 0.808511 (-4360 4535);
PAINT GREEN (-4360 4535);
DISPLAY INVISIBLE (-4360 4535);
FORCEPROP 1 LAST OFFPAGE TRUE
J 2
(-4360 4455);
DISPLAY 0.808511 (-4360 4455);
PAINT GREEN (-4360 4455);
DISPLAY INVISIBLE (-4360 4455);
FORCEPROP 2 LAST PATH I471
J 0
(-4500 4450);
DISPLAY 1.021277 (-4500 4450);
DISPLAY INVISIBLE (-4500 4450);
FORCEADD OFFPAGE_IN..2
R 2
(-4350 4300);
FORCEPROP 2 LAST $XR0 24C10> 
J 0
(-4564 4300);
DISPLAY 0.638298 (-4564 4300);
PAINT MONO (-4564 4300);
FORCEPROP 1 LAST OFFPAGE TRUE
J 2
(-4360 4355);
DISPLAY 0.808511 (-4360 4355);
PAINT GREEN (-4360 4355);
DISPLAY INVISIBLE (-4360 4355);
FORCEPROP 1 LAST BODY_TYPE COMMENT
J 2
(-4360 4435);
DISPLAY 0.808511 (-4360 4435);
PAINT GREEN (-4360 4435);
DISPLAY INVISIBLE (-4360 4435);
FORCEPROP 1 LAST CDS_LMAN_SYM_OUTLINE -50,50,50,-50
J 2
(-4350 4300);
DISPLAY 0.468085 (-4350 4300);
PAINT GREEN (-4350 4300);
DISPLAY INVISIBLE (-4350 4300);
FORCEPROP 2 LAST CDS_LIB cls
J 0
(-4350 4300);
DISPLAY INVISIBLE (-4350 4300);
FORCEPROP 2 LAST PATH I472
J 0
(-4550 4350);
DISPLAY 1.021277 (-4550 4350);
DISPLAY INVISIBLE (-4550 4350);
FORCEADD TS3A5018PWR_TSSOP16..2
(-13850 2750);
FORCEPROP 1 LAST $LOCATION U30
J 2
(-13750 2150);
DISPLAY 1.212766 (-13750 2150);
PAINT GREEN (-13750 2150);
FORCEPROP 0 LAST CDS_LOCATION U30
J 0
(-13750 2250);
DISPLAY 1.021277 (-13750 2250);
DISPLAY INVISIBLE (-13750 2250);
FORCEPROP 0 LAST $SEC 2
J 0
(-13750 2250);
DISPLAY 0.680851 (-13750 2250);
PAINT MONO (-13750 2250);
DISPLAY INVISIBLE (-13750 2250);
FORCEPROP 0 LAST CDS_SEC 2
J 0
(-13750 2250);
DISPLAY 1.021277 (-13750 2250);
DISPLAY INVISIBLE (-13750 2250);
FORCEPROP 0 LASTPIN (-13650 2150) $PN 8
R 1
J 2
(-13660 2140);
DISPLAY 0.680851 (-13660 2140);
PAINT MONO (-13660 2140);
FORCEPROP 0 LASTPIN (-13650 2850) $PN 16
R 1
J 0
(-13660 2860);
DISPLAY 0.680851 (-13660 2860);
PAINT MONO (-13660 2860);
FORCEPROP 1 LAST CLS_PN G220-10324-01
J 2
(-13750 2050);
DISPLAY 1.212766 (-13750 2050);
PAINT GREEN (-13750 2050);
FORCEPROP 1 LAST PATH I473
J 2
(-13900 2800);
DISPLAY 1.212766 (-13900 2800);
PAINT GREEN (-13900 2800);
DISPLAY INVISIBLE (-13900 2800);
FORCEPROP 2 LAST CDS_LIB stdlogic
J 0
(-13850 2750);
DISPLAY INVISIBLE (-13850 2750);
FORCEPROP 1 LAST CDS_LMAN_SYM_OUTLINE 0,0,400,-500
J 0
(-13850 2750);
DISPLAY 0.468085 (-13850 2750);
PAINT GREEN (-13850 2750);
DISPLAY INVISIBLE (-13850 2750);
FORCEADD CAPACITOR..2
R 2
(-13200 2550);
FORCEPROP 1 LAST $LOCATION C89
J 2
(-12900 2500);
DISPLAY 1.212766 (-12900 2500);
PAINT GREEN (-12900 2500);
FORCEPROP 0 LAST CDS_LOCATION C89
J 0
(-13100 2750);
DISPLAY 1.021277 (-13100 2750);
DISPLAY INVISIBLE (-13100 2750);
FORCEPROP 0 LAST $SEC 1
J 0
(-13100 2750);
DISPLAY 0.680851 (-13100 2750);
PAINT MONO (-13100 2750);
DISPLAY INVISIBLE (-13100 2750);
FORCEPROP 0 LAST CDS_SEC 1
J 0
(-13100 2750);
DISPLAY 1.021277 (-13100 2750);
DISPLAY INVISIBLE (-13100 2750);
FORCEPROP 0 LASTPIN (-13200 2650) $PN 1
R 1
J 0
(-13210 2660);
DISPLAY 0.680851 (-13210 2660);
PAINT MONO (-13210 2660);
FORCEPROP 0 LASTPIN (-13200 2400) $PN 2
R 1
J 2
(-13210 2390);
DISPLAY 0.680851 (-13210 2390);
PAINT MONO (-13210 2390);
FORCEPROP 0 LAST VOLTAGE 25V
J 0
(-13050 2400);
DISPLAY 1.021277 (-13050 2400);
FORCEPROP 0 LAST PACKAGE 0402
J 0
(-13050 2700);
DISPLAY 1.021277 (-13050 2700);
FORCEPROP 1 LAST VALUE 0.1UF
J 2
(-12750 2600);
DISPLAY 1.212766 (-12750 2600);
PAINT GREEN (-12750 2600);
FORCEPROP 1 LAST PATH I474
J 2
(-13100 2600);
DISPLAY 1.212766 (-13100 2600);
PAINT GREEN (-13100 2600);
DISPLAY INVISIBLE (-13100 2600);
FORCEPROP 1 LAST CDS_LMAN_SYM_OUTLINE -50,0,50,-50
J 2
(-13200 2550);
DISPLAY 0.468085 (-13200 2550);
PAINT GREEN (-13200 2550);
DISPLAY INVISIBLE (-13200 2550);
FORCEPROP 2 LAST CDS_LIB passive
J 0
(-13200 2550);
DISPLAY INVISIBLE (-13200 2550);
FORCEPROP 1 LAST CLS_PN G105-0B104-EK
J 2
(-13100 2600);
DISPLAY 1.212766 (-13100 2600);
PAINT GREEN (-13100 2600);
DISPLAY INVISIBLE (-13100 2600);
FORCEPROP 1 LAST TOLERANCE 10%
J 2
(-13050 2650);
DISPLAY 1.212766 (-13050 2650);
PAINT GREEN (-13050 2650);
DISPLAY INVISIBLE (-13050 2650);
FORCEADD GND_SG..1
(-12400 2000);
FORCEPROP 3 LASTPIN (-12350 2050) SIG_NAME SG\g
J 0
(-12340 2060);
DISPLAY 0.659574 (-12340 2060);
PAINT MONO (-12340 2060);
DISPLAY INVISIBLE (-12340 2060);
FORCEPROP 1 LAST HDL_POWER SG
J 1
(-12345 1905);
DISPLAY 0.808511 (-12345 1905);
PAINT GREEN (-12345 1905);
FORCEPROP 1 LAST PATH I475
J 0
(-12365 2000);
DISPLAY 0.808511 (-12365 2000);
PAINT GREEN (-12365 2000);
DISPLAY INVISIBLE (-12365 2000);
FORCEPROP 1 LAST BODY_TYPE PLUMBING
J 0
(-12385 1985);
DISPLAY 0.808511 (-12385 1985);
PAINT GREEN (-12385 1985);
DISPLAY INVISIBLE (-12385 1985);
FORCEPROP 2 LAST CDS_LIB cls
J 0
(-12400 2000);
DISPLAY INVISIBLE (-12400 2000);
FORCEPROP 1 LAST CDS_LMAN_SYM_OUTLINE 0,0,100,-50
J 0
(-12400 2000);
DISPLAY 0.468085 (-12400 2000);
PAINT GREEN (-12400 2000);
DISPLAY INVISIBLE (-12400 2000);
FORCEADD CAPACITOR..2
R 2
(-11900 2550);
FORCEPROP 1 LAST $LOCATION C92
J 2
(-11650 2500);
DISPLAY 1.212766 (-11650 2500);
PAINT GREEN (-11650 2500);
FORCEPROP 0 LAST CDS_LOCATION C92
J 0
(-11800 2750);
DISPLAY 1.021277 (-11800 2750);
DISPLAY INVISIBLE (-11800 2750);
FORCEPROP 0 LAST $SEC 1
J 0
(-11800 2750);
DISPLAY 0.680851 (-11800 2750);
PAINT MONO (-11800 2750);
DISPLAY INVISIBLE (-11800 2750);
FORCEPROP 0 LAST CDS_SEC 1
J 0
(-11800 2750);
DISPLAY 1.021277 (-11800 2750);
DISPLAY INVISIBLE (-11800 2750);
FORCEPROP 0 LASTPIN (-11900 2650) $PN 1
R 1
J 0
(-11910 2660);
DISPLAY 0.680851 (-11910 2660);
PAINT MONO (-11910 2660);
FORCEPROP 0 LASTPIN (-11900 2400) $PN 2
R 1
J 2
(-11910 2390);
DISPLAY 0.680851 (-11910 2390);
PAINT MONO (-11910 2390);
FORCEPROP 0 LAST PACKAGE 0402
J 0
(-11800 2700);
DISPLAY 1.021277 (-11800 2700);
FORCEPROP 1 LAST VALUE 0.1UF
J 2
(-11500 2600);
DISPLAY 1.212766 (-11500 2600);
PAINT GREEN (-11500 2600);
FORCEPROP 0 LAST VOLTAGE 25V
J 0
(-11800 2400);
DISPLAY 1.021277 (-11800 2400);
FORCEPROP 1 LAST PATH I476
J 2
(-11800 2600);
DISPLAY 1.212766 (-11800 2600);
PAINT GREEN (-11800 2600);
DISPLAY INVISIBLE (-11800 2600);
FORCEPROP 2 LAST CDS_LIB passive
J 0
(-11900 2550);
DISPLAY INVISIBLE (-11900 2550);
FORCEPROP 1 LAST CDS_LMAN_SYM_OUTLINE -50,0,50,-50
J 2
(-11900 2550);
DISPLAY 0.468085 (-11900 2550);
PAINT GREEN (-11900 2550);
DISPLAY INVISIBLE (-11900 2550);
FORCEPROP 1 LAST TOLERANCE 10%
J 2
(-11750 2650);
DISPLAY 1.212766 (-11750 2650);
PAINT GREEN (-11750 2650);
DISPLAY INVISIBLE (-11750 2650);
FORCEPROP 1 LAST CLS_PN G105-0B104-EK
J 2
(-11800 2600);
DISPLAY 1.212766 (-11800 2600);
PAINT GREEN (-11800 2600);
DISPLAY INVISIBLE (-11800 2600);
FORCEADD TS3A5018PWR_TSSOP16..2
(-12550 2750);
FORCEPROP 1 LAST $LOCATION U37
J 2
(-12450 2150);
DISPLAY 1.212766 (-12450 2150);
PAINT GREEN (-12450 2150);
FORCEPROP 0 LAST CDS_LOCATION U37
J 0
(-12450 2250);
DISPLAY 1.021277 (-12450 2250);
DISPLAY INVISIBLE (-12450 2250);
FORCEPROP 0 LAST $SEC 2
J 0
(-12450 2250);
DISPLAY 0.680851 (-12450 2250);
PAINT MONO (-12450 2250);
DISPLAY INVISIBLE (-12450 2250);
FORCEPROP 0 LAST CDS_SEC 2
J 0
(-12450 2250);
DISPLAY 1.021277 (-12450 2250);
DISPLAY INVISIBLE (-12450 2250);
FORCEPROP 0 LASTPIN (-12350 2150) $PN 8
R 1
J 2
(-12360 2140);
DISPLAY 0.680851 (-12360 2140);
PAINT MONO (-12360 2140);
FORCEPROP 0 LASTPIN (-12350 2850) $PN 16
R 1
J 0
(-12360 2860);
DISPLAY 0.680851 (-12360 2860);
PAINT MONO (-12360 2860);
FORCEPROP 1 LAST CLS_PN G220-10324-01
J 2
(-12400 2050);
DISPLAY 1.212766 (-12400 2050);
PAINT GREEN (-12400 2050);
FORCEPROP 1 LAST PATH I478
J 2
(-12600 2800);
DISPLAY 1.212766 (-12600 2800);
PAINT GREEN (-12600 2800);
DISPLAY INVISIBLE (-12600 2800);
FORCEPROP 2 LAST CDS_LIB stdlogic
J 0
(-12550 2750);
DISPLAY INVISIBLE (-12550 2750);
FORCEPROP 1 LAST CDS_LMAN_SYM_OUTLINE 0,0,400,-500
J 0
(-12550 2750);
DISPLAY 0.468085 (-12550 2750);
PAINT GREEN (-12550 2750);
DISPLAY INVISIBLE (-12550 2750);
FORCEADD VCC..1
(-13700 3000);
FORCEPROP 3 LASTPIN (-13650 2950) SIG_NAME XP3R3V_FPGA\g
J 0
(-13640 2960);
DISPLAY 0.659574 (-13640 2960);
PAINT MONO (-13640 2960);
DISPLAY INVISIBLE (-13640 2960);
FORCEPROP 0 LAST VOLTAGE 3.3V
J 0
(-13900 3100);
DISPLAY 1.021277 (-13900 3100);
DISPLAY BOTH (-13900 3100);
FORCEPROP 1 LAST HDL_POWER XP3R3V_FPGA
J 1
(-13645 3055);
DISPLAY 1.021277 (-13645 3055);
PAINT GREEN (-13645 3055);
FORCEPROP 1 LAST PATH I479
J 0
(-13665 3090);
DISPLAY 0.808511 (-13665 3090);
PAINT GREEN (-13665 3090);
DISPLAY INVISIBLE (-13665 3090);
FORCEPROP 1 LAST CDS_LMAN_SYM_OUTLINE -250,250,250,-250
J 0
(-13700 3000);
DISPLAY 0.468085 (-13700 3000);
PAINT GREEN (-13700 3000);
DISPLAY INVISIBLE (-13700 3000);
FORCEPROP 2 LAST CDS_LIB cls
J 0
(-13700 3000);
DISPLAY INVISIBLE (-13700 3000);
FORCEPROP 1 LAST BODY_TYPE PLUMBING
J 0
(-13745 2957);
DISPLAY 0.340426 (-13745 2957);
PAINT GREEN (-13745 2957);
DISPLAY INVISIBLE (-13745 2957);
FORCEADD GND_SG..1
(-13700 2000);
FORCEPROP 3 LASTPIN (-13650 2050) SIG_NAME SG\g
J 0
(-13640 2060);
DISPLAY 0.659574 (-13640 2060);
PAINT MONO (-13640 2060);
DISPLAY INVISIBLE (-13640 2060);
FORCEPROP 1 LAST HDL_POWER SG
J 1
(-13645 1905);
DISPLAY 0.808511 (-13645 1905);
PAINT GREEN (-13645 1905);
FORCEPROP 1 LAST PATH I480
J 0
(-13665 2000);
DISPLAY 0.808511 (-13665 2000);
PAINT GREEN (-13665 2000);
DISPLAY INVISIBLE (-13665 2000);
FORCEPROP 2 LAST CDS_LIB cls
J 0
(-13700 2000);
DISPLAY INVISIBLE (-13700 2000);
FORCEPROP 1 LAST CDS_LMAN_SYM_OUTLINE 0,0,100,-50
J 0
(-13700 2000);
DISPLAY 0.468085 (-13700 2000);
PAINT GREEN (-13700 2000);
DISPLAY INVISIBLE (-13700 2000);
FORCEPROP 1 LAST BODY_TYPE PLUMBING
J 0
(-13685 1985);
DISPLAY 0.808511 (-13685 1985);
PAINT GREEN (-13685 1985);
DISPLAY INVISIBLE (-13685 1985);
FORCEADD TS3A5018PWR_TSSOP16..2
(-11300 2750);
FORCEPROP 1 LAST $LOCATION U38
J 2
(-11250 2100);
DISPLAY 1.212766 (-11250 2100);
PAINT GREEN (-11250 2100);
FORCEPROP 0 LAST CDS_LOCATION U38
J 0
(-11250 2200);
DISPLAY 1.021277 (-11250 2200);
DISPLAY INVISIBLE (-11250 2200);
FORCEPROP 0 LAST $SEC 2
J 0
(-11250 2200);
DISPLAY 0.680851 (-11250 2200);
PAINT MONO (-11250 2200);
DISPLAY INVISIBLE (-11250 2200);
FORCEPROP 0 LAST CDS_SEC 2
J 0
(-11250 2200);
DISPLAY 1.021277 (-11250 2200);
DISPLAY INVISIBLE (-11250 2200);
FORCEPROP 0 LASTPIN (-11100 2150) $PN 8
R 1
J 2
(-11110 2140);
DISPLAY 0.680851 (-11110 2140);
PAINT MONO (-11110 2140);
FORCEPROP 0 LASTPIN (-11100 2850) $PN 16
R 1
J 0
(-11110 2860);
DISPLAY 0.680851 (-11110 2860);
PAINT MONO (-11110 2860);
FORCEPROP 1 LAST CLS_PN G220-10324-01
J 2
(-11200 2000);
DISPLAY 1.212766 (-11200 2000);
PAINT GREEN (-11200 2000);
FORCEPROP 1 LAST PATH I481
J 2
(-11350 2800);
DISPLAY 1.212766 (-11350 2800);
PAINT GREEN (-11350 2800);
DISPLAY INVISIBLE (-11350 2800);
FORCEPROP 1 LAST CDS_LMAN_SYM_OUTLINE 0,0,400,-500
J 0
(-11300 2750);
DISPLAY 0.468085 (-11300 2750);
PAINT GREEN (-11300 2750);
DISPLAY INVISIBLE (-11300 2750);
FORCEPROP 2 LAST CDS_LIB stdlogic
J 0
(-11300 2750);
DISPLAY INVISIBLE (-11300 2750);
FORCEADD CAPACITOR..2
R 2
(-10650 2550);
FORCEPROP 1 LAST $LOCATION C97
J 2
(-10400 2500);
DISPLAY 1.212766 (-10400 2500);
PAINT GREEN (-10400 2500);
FORCEPROP 0 LAST CDS_LOCATION C97
J 0
(-10550 2750);
DISPLAY 1.021277 (-10550 2750);
DISPLAY INVISIBLE (-10550 2750);
FORCEPROP 0 LAST $SEC 1
J 0
(-10550 2750);
DISPLAY 0.680851 (-10550 2750);
PAINT MONO (-10550 2750);
DISPLAY INVISIBLE (-10550 2750);
FORCEPROP 0 LAST CDS_SEC 1
J 0
(-10550 2750);
DISPLAY 1.021277 (-10550 2750);
DISPLAY INVISIBLE (-10550 2750);
FORCEPROP 0 LASTPIN (-10650 2650) $PN 1
R 1
J 0
(-10660 2660);
DISPLAY 0.680851 (-10660 2660);
PAINT MONO (-10660 2660);
FORCEPROP 0 LASTPIN (-10650 2400) $PN 2
R 1
J 2
(-10660 2390);
DISPLAY 0.680851 (-10660 2390);
PAINT MONO (-10660 2390);
FORCEPROP 1 LAST VALUE 0.1UF
J 2
(-10250 2600);
DISPLAY 1.212766 (-10250 2600);
PAINT GREEN (-10250 2600);
FORCEPROP 0 LAST PACKAGE 0402
J 0
(-10550 2700);
DISPLAY 1.021277 (-10550 2700);
FORCEPROP 0 LAST VOLTAGE 25V
J 0
(-10550 2400);
DISPLAY 1.021277 (-10550 2400);
FORCEPROP 1 LAST PATH I482
J 2
(-10550 2600);
DISPLAY 1.212766 (-10550 2600);
PAINT GREEN (-10550 2600);
DISPLAY INVISIBLE (-10550 2600);
FORCEPROP 2 LAST CDS_LIB passive
J 0
(-10650 2550);
DISPLAY INVISIBLE (-10650 2550);
FORCEPROP 1 LAST CDS_LMAN_SYM_OUTLINE -50,0,50,-50
J 2
(-10650 2550);
DISPLAY 0.468085 (-10650 2550);
PAINT GREEN (-10650 2550);
DISPLAY INVISIBLE (-10650 2550);
FORCEPROP 1 LAST TOLERANCE 10%
J 2
(-10500 2650);
DISPLAY 1.212766 (-10500 2650);
PAINT GREEN (-10500 2650);
DISPLAY INVISIBLE (-10500 2650);
FORCEPROP 1 LAST CLS_PN G105-0B104-EK
J 2
(-10550 2600);
DISPLAY 1.212766 (-10550 2600);
PAINT GREEN (-10550 2600);
DISPLAY INVISIBLE (-10550 2600);
FORCEADD GND_SG..1
(-11150 2000);
FORCEPROP 3 LASTPIN (-11100 2050) SIG_NAME SG\g
J 0
(-11090 2060);
DISPLAY 0.659574 (-11090 2060);
PAINT MONO (-11090 2060);
DISPLAY INVISIBLE (-11090 2060);
FORCEPROP 1 LAST HDL_POWER SG
J 1
(-11095 1905);
DISPLAY 0.808511 (-11095 1905);
PAINT GREEN (-11095 1905);
FORCEPROP 1 LAST PATH I484
J 0
(-11115 2000);
DISPLAY 0.808511 (-11115 2000);
PAINT GREEN (-11115 2000);
DISPLAY INVISIBLE (-11115 2000);
FORCEPROP 1 LAST BODY_TYPE PLUMBING
J 0
(-11135 1985);
DISPLAY 0.808511 (-11135 1985);
PAINT GREEN (-11135 1985);
DISPLAY INVISIBLE (-11135 1985);
FORCEPROP 1 LAST CDS_LMAN_SYM_OUTLINE 0,0,100,-50
J 0
(-11150 2000);
DISPLAY 0.468085 (-11150 2000);
PAINT GREEN (-11150 2000);
DISPLAY INVISIBLE (-11150 2000);
FORCEPROP 2 LAST CDS_LIB cls
J 0
(-11150 2000);
DISPLAY INVISIBLE (-11150 2000);
FORCEADD NLASB3157DFT2G_SC88..2
(-3650 2750);
FORCEPROP 1 LAST $LOCATION U39
J 2
(-3550 2150);
DISPLAY 1.212766 (-3550 2150);
PAINT GREEN (-3550 2150);
FORCEPROP 0 LAST CDS_LOCATION U39
J 0
(-3550 2250);
DISPLAY 1.021277 (-3550 2250);
DISPLAY INVISIBLE (-3550 2250);
FORCEPROP 0 LAST $SEC 2
J 0
(-3550 2250);
DISPLAY 0.680851 (-3550 2250);
PAINT MONO (-3550 2250);
DISPLAY INVISIBLE (-3550 2250);
FORCEPROP 0 LAST CDS_SEC 2
J 0
(-3550 2250);
DISPLAY 1.021277 (-3550 2250);
DISPLAY INVISIBLE (-3550 2250);
FORCEPROP 0 LASTPIN (-3450 2150) $PN 2
R 1
J 2
(-3460 2140);
DISPLAY 0.680851 (-3460 2140);
PAINT MONO (-3460 2140);
FORCEPROP 0 LASTPIN (-3450 2850) $PN 5
R 1
J 0
(-3460 2860);
DISPLAY 0.680851 (-3460 2860);
PAINT MONO (-3460 2860);
FORCEPROP 1 LAST CLS_PN G223-10187-01
J 2
(-3550 2050);
DISPLAY 1.212766 (-3550 2050);
PAINT GREEN (-3550 2050);
FORCEPROP 1 LAST CDS_LMAN_SYM_OUTLINE 0,0,400,-500
J 0
(-3650 2750);
DISPLAY 0.468085 (-3650 2750);
PAINT GREEN (-3650 2750);
DISPLAY INVISIBLE (-3650 2750);
FORCEPROP 2 LAST CDS_LIB interface
J 0
(-3650 2750);
DISPLAY INVISIBLE (-3650 2750);
FORCEPROP 1 LAST PATH I485
J 2
(-3700 2800);
DISPLAY 1.212766 (-3700 2800);
PAINT GREEN (-3700 2800);
DISPLAY INVISIBLE (-3700 2800);
FORCEADD CAPACITOR..2
R 2
(-3000 2550);
FORCEPROP 1 LAST $LOCATION C123
J 2
(-2700 2500);
DISPLAY 1.212766 (-2700 2500);
PAINT GREEN (-2700 2500);
FORCEPROP 0 LAST CDS_LOCATION C123
J 0
(-2900 2750);
DISPLAY 1.021277 (-2900 2750);
DISPLAY INVISIBLE (-2900 2750);
FORCEPROP 0 LAST $SEC 1
J 0
(-2900 2750);
DISPLAY 0.680851 (-2900 2750);
PAINT MONO (-2900 2750);
DISPLAY INVISIBLE (-2900 2750);
FORCEPROP 0 LAST CDS_SEC 1
J 0
(-2900 2750);
DISPLAY 1.021277 (-2900 2750);
DISPLAY INVISIBLE (-2900 2750);
FORCEPROP 0 LASTPIN (-3000 2650) $PN 1
R 1
J 0
(-3010 2660);
DISPLAY 0.680851 (-3010 2660);
PAINT MONO (-3010 2660);
FORCEPROP 0 LASTPIN (-3000 2400) $PN 2
R 1
J 2
(-3010 2390);
DISPLAY 0.680851 (-3010 2390);
PAINT MONO (-3010 2390);
FORCEPROP 1 LAST VALUE 0.1UF
J 2
(-2600 2600);
DISPLAY 1.212766 (-2600 2600);
PAINT GREEN (-2600 2600);
FORCEPROP 0 LAST PACKAGE 0402
J 0
(-2850 2700);
DISPLAY 1.021277 (-2850 2700);
FORCEPROP 0 LAST VOLTAGE 25V
J 0
(-2850 2400);
DISPLAY 1.021277 (-2850 2400);
FORCEPROP 2 LAST CDS_LIB passive
J 0
(-3000 2550);
DISPLAY INVISIBLE (-3000 2550);
FORCEPROP 1 LAST CDS_LMAN_SYM_OUTLINE -50,0,50,-50
J 2
(-3000 2550);
DISPLAY 0.468085 (-3000 2550);
PAINT GREEN (-3000 2550);
DISPLAY INVISIBLE (-3000 2550);
FORCEPROP 1 LAST CLS_PN G105-0B104-EK
J 2
(-2900 2600);
DISPLAY 1.212766 (-2900 2600);
PAINT GREEN (-2900 2600);
DISPLAY INVISIBLE (-2900 2600);
FORCEPROP 1 LAST TOLERANCE 10%
J 2
(-2850 2650);
DISPLAY 1.212766 (-2850 2650);
PAINT GREEN (-2850 2650);
DISPLAY INVISIBLE (-2850 2650);
FORCEPROP 1 LAST PATH I486
J 2
(-2900 2600);
DISPLAY 1.212766 (-2900 2600);
PAINT GREEN (-2900 2600);
DISPLAY INVISIBLE (-2900 2600);
FORCEADD VCC..1
(-3500 3000);
FORCEPROP 3 LASTPIN (-3450 2950) SIG_NAME XP3R3V_FPGA\g
J 0
(-3440 2960);
DISPLAY 0.659574 (-3440 2960);
PAINT MONO (-3440 2960);
DISPLAY INVISIBLE (-3440 2960);
FORCEPROP 1 LAST HDL_POWER XP3R3V_FPGA
J 1
(-3445 3055);
DISPLAY 1.021277 (-3445 3055);
PAINT GREEN (-3445 3055);
FORCEPROP 0 LAST VOLTAGE 3.3V
J 0
(-3700 3100);
DISPLAY 1.021277 (-3700 3100);
DISPLAY BOTH (-3700 3100);
FORCEPROP 2 LAST CDS_LIB cls
J 0
(-3500 3000);
DISPLAY INVISIBLE (-3500 3000);
FORCEPROP 1 LAST CDS_LMAN_SYM_OUTLINE -250,250,250,-250
J 0
(-3500 3000);
DISPLAY 0.468085 (-3500 3000);
PAINT GREEN (-3500 3000);
DISPLAY INVISIBLE (-3500 3000);
FORCEPROP 1 LAST BODY_TYPE PLUMBING
J 0
(-3545 2957);
DISPLAY 0.340426 (-3545 2957);
PAINT GREEN (-3545 2957);
DISPLAY INVISIBLE (-3545 2957);
FORCEPROP 1 LAST PATH I487
J 0
(-3465 3090);
DISPLAY 0.808511 (-3465 3090);
PAINT GREEN (-3465 3090);
DISPLAY INVISIBLE (-3465 3090);
FORCEADD GND_SG..1
(-3500 2000);
FORCEPROP 3 LASTPIN (-3450 2050) SIG_NAME SG\g
J 0
(-3440 2060);
DISPLAY 0.659574 (-3440 2060);
PAINT MONO (-3440 2060);
DISPLAY INVISIBLE (-3440 2060);
FORCEPROP 1 LAST HDL_POWER SG
J 1
(-3445 1905);
DISPLAY 0.808511 (-3445 1905);
PAINT GREEN (-3445 1905);
FORCEPROP 2 LAST CDS_LIB cls
J 0
(-3500 2000);
DISPLAY INVISIBLE (-3500 2000);
FORCEPROP 1 LAST CDS_LMAN_SYM_OUTLINE 0,0,100,-50
J 0
(-3500 2000);
DISPLAY 0.468085 (-3500 2000);
PAINT GREEN (-3500 2000);
DISPLAY INVISIBLE (-3500 2000);
FORCEPROP 1 LAST BODY_TYPE PLUMBING
J 0
(-3485 1985);
DISPLAY 0.808511 (-3485 1985);
PAINT GREEN (-3485 1985);
DISPLAY INVISIBLE (-3485 1985);
FORCEPROP 1 LAST PATH I488
J 0
(-3465 2000);
DISPLAY 0.808511 (-3465 2000);
PAINT GREEN (-3465 2000);
DISPLAY INVISIBLE (-3465 2000);
FORCEADD VCC..1
(-4850 3000);
FORCEPROP 3 LASTPIN (-4800 2950) SIG_NAME XP3R3V_FPGA\g
J 0
(-4790 2960);
DISPLAY 0.659574 (-4790 2960);
PAINT MONO (-4790 2960);
DISPLAY INVISIBLE (-4790 2960);
FORCEPROP 1 LAST HDL_POWER XP3R3V_FPGA
J 1
(-4795 3055);
DISPLAY 1.021277 (-4795 3055);
PAINT GREEN (-4795 3055);
FORCEPROP 0 LAST VOLTAGE 3.3V
J 0
(-5050 3100);
DISPLAY 1.021277 (-5050 3100);
DISPLAY BOTH (-5050 3100);
FORCEPROP 2 LAST CDS_LIB cls
J 0
(-4850 3000);
DISPLAY INVISIBLE (-4850 3000);
FORCEPROP 1 LAST CDS_LMAN_SYM_OUTLINE -250,250,250,-250
J 0
(-4850 3000);
DISPLAY 0.468085 (-4850 3000);
PAINT GREEN (-4850 3000);
DISPLAY INVISIBLE (-4850 3000);
FORCEPROP 1 LAST BODY_TYPE PLUMBING
J 0
(-4895 2957);
DISPLAY 0.340426 (-4895 2957);
PAINT GREEN (-4895 2957);
DISPLAY INVISIBLE (-4895 2957);
FORCEPROP 1 LAST PATH I489
J 0
(-4815 3090);
DISPLAY 0.808511 (-4815 3090);
PAINT GREEN (-4815 3090);
DISPLAY INVISIBLE (-4815 3090);
FORCEADD CAPACITOR..2
R 2
(-4350 2550);
FORCEPROP 1 LAST $LOCATION C102
J 2
(-4050 2500);
DISPLAY 1.212766 (-4050 2500);
PAINT GREEN (-4050 2500);
FORCEPROP 0 LAST CDS_LOCATION C102
J 0
(-4250 2750);
DISPLAY 1.021277 (-4250 2750);
DISPLAY INVISIBLE (-4250 2750);
FORCEPROP 0 LAST $SEC 1
J 0
(-4250 2750);
DISPLAY 0.680851 (-4250 2750);
PAINT MONO (-4250 2750);
DISPLAY INVISIBLE (-4250 2750);
FORCEPROP 0 LAST CDS_SEC 1
J 0
(-4250 2750);
DISPLAY 1.021277 (-4250 2750);
DISPLAY INVISIBLE (-4250 2750);
FORCEPROP 0 LASTPIN (-4350 2650) $PN 1
R 1
J 0
(-4360 2660);
DISPLAY 0.680851 (-4360 2660);
PAINT MONO (-4360 2660);
FORCEPROP 0 LASTPIN (-4350 2400) $PN 2
R 1
J 2
(-4360 2390);
DISPLAY 0.680851 (-4360 2390);
PAINT MONO (-4360 2390);
FORCEPROP 1 LAST VALUE 0.1UF
J 2
(-3950 2600);
DISPLAY 1.212766 (-3950 2600);
PAINT GREEN (-3950 2600);
FORCEPROP 0 LAST VOLTAGE 25V
J 0
(-4250 2400);
DISPLAY 1.021277 (-4250 2400);
FORCEPROP 0 LAST PACKAGE 0402
J 0
(-4250 2700);
DISPLAY 1.021277 (-4250 2700);
FORCEPROP 2 LAST CDS_LIB passive
J 0
(-4350 2550);
DISPLAY INVISIBLE (-4350 2550);
FORCEPROP 1 LAST CDS_LMAN_SYM_OUTLINE -50,0,50,-50
J 2
(-4350 2550);
DISPLAY 0.468085 (-4350 2550);
PAINT GREEN (-4350 2550);
DISPLAY INVISIBLE (-4350 2550);
FORCEPROP 1 LAST CLS_PN G105-0B104-EK
J 2
(-4250 2600);
DISPLAY 1.212766 (-4250 2600);
PAINT GREEN (-4250 2600);
DISPLAY INVISIBLE (-4250 2600);
FORCEPROP 1 LAST TOLERANCE 10%
J 2
(-4200 2650);
DISPLAY 1.212766 (-4200 2650);
PAINT GREEN (-4200 2650);
DISPLAY INVISIBLE (-4200 2650);
FORCEPROP 1 LAST PATH I490
J 2
(-4250 2600);
DISPLAY 1.212766 (-4250 2600);
PAINT GREEN (-4250 2600);
DISPLAY INVISIBLE (-4250 2600);
FORCEADD NLASB3157DFT2G_SC88..2
(-5000 2750);
FORCEPROP 1 LAST $LOCATION U40
J 2
(-4900 2150);
DISPLAY 1.212766 (-4900 2150);
PAINT GREEN (-4900 2150);
FORCEPROP 0 LAST CDS_LOCATION U40
J 0
(-4900 2250);
DISPLAY 1.021277 (-4900 2250);
DISPLAY INVISIBLE (-4900 2250);
FORCEPROP 0 LAST $SEC 2
J 0
(-4900 2250);
DISPLAY 0.680851 (-4900 2250);
PAINT MONO (-4900 2250);
DISPLAY INVISIBLE (-4900 2250);
FORCEPROP 0 LAST CDS_SEC 2
J 0
(-4900 2250);
DISPLAY 1.021277 (-4900 2250);
DISPLAY INVISIBLE (-4900 2250);
FORCEPROP 0 LASTPIN (-4800 2150) $PN 2
R 1
J 2
(-4810 2140);
DISPLAY 0.680851 (-4810 2140);
PAINT MONO (-4810 2140);
FORCEPROP 0 LASTPIN (-4800 2850) $PN 5
R 1
J 0
(-4810 2860);
DISPLAY 0.680851 (-4810 2860);
PAINT MONO (-4810 2860);
FORCEPROP 1 LAST CLS_PN G223-10187-01
J 2
(-4900 2050);
DISPLAY 1.212766 (-4900 2050);
PAINT GREEN (-4900 2050);
FORCEPROP 1 LAST CDS_LMAN_SYM_OUTLINE 0,0,400,-500
J 0
(-5000 2750);
DISPLAY 0.468085 (-5000 2750);
PAINT GREEN (-5000 2750);
DISPLAY INVISIBLE (-5000 2750);
FORCEPROP 2 LAST CDS_LIB interface
J 0
(-5000 2750);
DISPLAY INVISIBLE (-5000 2750);
FORCEPROP 1 LAST PATH I491
J 2
(-5050 2800);
DISPLAY 1.212766 (-5050 2800);
PAINT GREEN (-5050 2800);
DISPLAY INVISIBLE (-5050 2800);
FORCEADD GND_SG..1
(-4850 2000);
FORCEPROP 3 LASTPIN (-4800 2050) SIG_NAME SG\g
J 0
(-4790 2060);
DISPLAY 0.659574 (-4790 2060);
PAINT MONO (-4790 2060);
DISPLAY INVISIBLE (-4790 2060);
FORCEPROP 1 LAST HDL_POWER SG
J 1
(-4795 1905);
DISPLAY 0.808511 (-4795 1905);
PAINT GREEN (-4795 1905);
FORCEPROP 2 LAST CDS_LIB cls
J 0
(-4850 2000);
DISPLAY INVISIBLE (-4850 2000);
FORCEPROP 1 LAST CDS_LMAN_SYM_OUTLINE 0,0,100,-50
J 0
(-4850 2000);
DISPLAY 0.468085 (-4850 2000);
PAINT GREEN (-4850 2000);
DISPLAY INVISIBLE (-4850 2000);
FORCEPROP 1 LAST BODY_TYPE PLUMBING
J 0
(-4835 1985);
DISPLAY 0.808511 (-4835 1985);
PAINT GREEN (-4835 1985);
DISPLAY INVISIBLE (-4835 1985);
FORCEPROP 1 LAST PATH I492
J 0
(-4815 2000);
DISPLAY 0.808511 (-4815 2000);
PAINT GREEN (-4815 2000);
DISPLAY INVISIBLE (-4815 2000);
FORCEADD RESISTOR..1
(-7450 3500);
FORCEPROP 1 LAST $LOCATION R464
J 2
(-7650 3500);
DISPLAY 0.978723 (-7650 3500);
PAINT GREEN (-7650 3500);
FORCEPROP 0 LAST CDS_LOCATION R464
J 0
(-7200 3550);
DISPLAY 1.021277 (-7200 3550);
DISPLAY INVISIBLE (-7200 3550);
FORCEPROP 0 LAST $SEC 1
J 0
(-7200 3550);
DISPLAY 0.680851 (-7200 3550);
PAINT MONO (-7200 3550);
DISPLAY INVISIBLE (-7200 3550);
FORCEPROP 0 LAST CDS_SEC 1
J 0
(-7200 3550);
DISPLAY 1.021277 (-7200 3550);
DISPLAY INVISIBLE (-7200 3550);
FORCEPROP 0 LASTPIN (-7550 3500) $PN 1
J 2
(-7560 3510);
DISPLAY 0.680851 (-7560 3510);
PAINT MONO (-7560 3510);
FORCEPROP 0 LASTPIN (-7300 3500) $PN 2
J 0
(-7290 3510);
DISPLAY 0.680851 (-7290 3510);
PAINT MONO (-7290 3510);
FORCEPROP 0 LAST PACKAGE 0402
J 0
(-7500 3500);
DISPLAY 0.808511 (-7500 3500);
FORCEPROP 1 LAST VALUE 0OHM
J 0
(-7200 3500);
DISPLAY 0.978723 (-7200 3500);
PAINT GREEN (-7200 3500);
FORCEPROP 0 LAST NO_ASSY TRUE
J 0
(-7650 3450);
DISPLAY 0.808511 (-7650 3450);
DISPLAY BOTH (-7650 3450);
FORCEPROP 2 LAST CDS_LIB passive
J 0
(-7450 3500);
DISPLAY INVISIBLE (-7450 3500);
FORCEPROP 1 LAST PATH I493
J 0
(-7647 3605);
DISPLAY 1.212766 (-7647 3605);
PAINT GREEN (-7647 3605);
DISPLAY INVISIBLE (-7647 3605);
FORCEPROP 1 LAST CDS_LMAN_SYM_OUTLINE -50,50,100,-50
J 0
(-7450 3500);
DISPLAY 0.468085 (-7450 3500);
PAINT GREEN (-7450 3500);
DISPLAY INVISIBLE (-7450 3500);
FORCEPROP 1 LAST CLS_PN G155-100R0-J0
J 0
(-7586 3700);
DISPLAY 1.212766 (-7586 3700);
PAINT GREEN (-7586 3700);
DISPLAY INVISIBLE (-7586 3700);
FORCEPROP 1 LAST TOLERANCE -
J 0
(-7647 3755);
DISPLAY 1.212766 (-7647 3755);
PAINT GREEN (-7647 3755);
DISPLAY INVISIBLE (-7647 3755);
FORCEADD RESISTOR..1
(-7450 2850);
FORCEPROP 1 LAST $LOCATION R465
J 2
(-7650 2850);
DISPLAY 0.978723 (-7650 2850);
PAINT GREEN (-7650 2850);
FORCEPROP 0 LAST CDS_LOCATION R465
J 0
(-7200 2900);
DISPLAY 1.021277 (-7200 2900);
DISPLAY INVISIBLE (-7200 2900);
FORCEPROP 0 LAST $SEC 1
J 0
(-7200 2900);
DISPLAY 0.680851 (-7200 2900);
PAINT MONO (-7200 2900);
DISPLAY INVISIBLE (-7200 2900);
FORCEPROP 0 LAST CDS_SEC 1
J 0
(-7200 2900);
DISPLAY 1.021277 (-7200 2900);
DISPLAY INVISIBLE (-7200 2900);
FORCEPROP 0 LASTPIN (-7550 2850) $PN 1
J 2
(-7560 2860);
DISPLAY 0.680851 (-7560 2860);
PAINT MONO (-7560 2860);
FORCEPROP 0 LASTPIN (-7300 2850) $PN 2
J 0
(-7290 2860);
DISPLAY 0.680851 (-7290 2860);
PAINT MONO (-7290 2860);
FORCEPROP 1 LAST VALUE 0OHM
J 0
(-7200 2850);
DISPLAY 0.978723 (-7200 2850);
PAINT GREEN (-7200 2850);
FORCEPROP 0 LAST NO_ASSY TRUE
J 0
(-7650 2800);
DISPLAY 0.808511 (-7650 2800);
DISPLAY BOTH (-7650 2800);
FORCEPROP 0 LAST PACKAGE 0402
J 0
(-7500 2850);
DISPLAY 0.808511 (-7500 2850);
FORCEPROP 1 LAST PATH I494
J 0
(-7647 2955);
DISPLAY 1.212766 (-7647 2955);
PAINT GREEN (-7647 2955);
DISPLAY INVISIBLE (-7647 2955);
FORCEPROP 2 LAST CDS_LIB passive
J 0
(-7450 2850);
DISPLAY INVISIBLE (-7450 2850);
FORCEPROP 1 LAST CDS_LMAN_SYM_OUTLINE -50,50,100,-50
J 0
(-7450 2850);
DISPLAY 0.468085 (-7450 2850);
PAINT GREEN (-7450 2850);
DISPLAY INVISIBLE (-7450 2850);
FORCEPROP 1 LAST CLS_PN G155-100R0-J0
J 0
(-7586 3050);
DISPLAY 1.212766 (-7586 3050);
PAINT GREEN (-7586 3050);
DISPLAY INVISIBLE (-7586 3050);
FORCEPROP 1 LAST TOLERANCE -
J 0
(-7647 3105);
DISPLAY 1.212766 (-7647 3105);
PAINT GREEN (-7647 3105);
DISPLAY INVISIBLE (-7647 3105);
FORCEADD CONN_USB_14P_GH4_F_RA_TH..1
(-13750 10450);
FORCEPROP 1 LAST LOCATION J13
J 0
(-13750 10500);
DISPLAY 1.212766 (-13750 10500);
PAINT GREEN (-13750 10500);
FORCEPROP 0 LAST $SEC 1
J 0
(-13750 10800);
DISPLAY 0.680851 (-13750 10800);
PAINT MONO (-13750 10800);
DISPLAY INVISIBLE (-13750 10800);
FORCEPROP 0 LAST CDS_SEC 1
J 0
(-13750 10800);
DISPLAY 1.021277 (-13750 10800);
DISPLAY INVISIBLE (-13750 10800);
FORCEPROP 0 LASTPIN (-13850 10050) $PN A5
J 2
(-13860 10060);
DISPLAY 0.680851 (-13860 10060);
PAINT MONO (-13860 10060);
FORCEPROP 0 LASTPIN (-12750 10050) $PN B5
J 0
(-12740 10060);
DISPLAY 0.680851 (-12740 10060);
PAINT MONO (-12740 10060);
FORCEPROP 0 LASTPIN (-13850 9750) $PN A7
J 2
(-13860 9760);
DISPLAY 0.680851 (-13860 9760);
PAINT MONO (-13860 9760);
FORCEPROP 0 LASTPIN (-13850 9850) $PN A6
J 2
(-13860 9860);
DISPLAY 0.680851 (-13860 9860);
PAINT MONO (-13860 9860);
FORCEPROP 0 LASTPIN (-12750 9750) $PN B7
J 0
(-12740 9760);
DISPLAY 0.680851 (-12740 9760);
PAINT MONO (-12740 9760);
FORCEPROP 0 LASTPIN (-12750 9850) $PN B6
J 0
(-12740 9860);
DISPLAY 0.680851 (-12740 9860);
PAINT MONO (-12740 9860);
FORCEPROP 0 LASTPIN (-13850 9250) $PN GH1
J 2
(-13860 9260);
DISPLAY 0.680851 (-13860 9260);
PAINT MONO (-13860 9260);
FORCEPROP 0 LASTPIN (-13850 9150) $PN GH2
J 2
(-13860 9160);
DISPLAY 0.680851 (-13860 9160);
PAINT MONO (-13860 9160);
FORCEPROP 0 LASTPIN (-12750 9250) $PN GH3
J 0
(-12740 9260);
DISPLAY 0.680851 (-12740 9260);
PAINT MONO (-12740 9260);
FORCEPROP 0 LASTPIN (-12750 9150) $PN GH4
J 0
(-12740 9160);
DISPLAY 0.680851 (-12740 9160);
PAINT MONO (-12740 9160);
FORCEPROP 0 LASTPIN (-13850 9550) $PN A1
J 2
(-13860 9560);
DISPLAY 0.680851 (-13860 9560);
PAINT MONO (-13860 9560);
FORCEPROP 0 LASTPIN (-13850 9450) $PN A12
J 2
(-13860 9460);
DISPLAY 0.680851 (-13860 9460);
PAINT MONO (-13860 9460);
FORCEPROP 0 LASTPIN (-12750 9550) $PN B1
J 0
(-12740 9560);
DISPLAY 0.680851 (-12740 9560);
PAINT MONO (-12740 9560);
FORCEPROP 0 LASTPIN (-12750 9450) $PN B12
J 0
(-12740 9460);
DISPLAY 0.680851 (-12740 9460);
PAINT MONO (-12740 9460);
FORCEPROP 0 LASTPIN (-13850 10350) $PN A4
J 2
(-13860 10360);
DISPLAY 0.680851 (-13860 10360);
PAINT MONO (-13860 10360);
FORCEPROP 0 LASTPIN (-13850 10250) $PN A9
J 2
(-13860 10260);
DISPLAY 0.680851 (-13860 10260);
PAINT MONO (-13860 10260);
FORCEPROP 0 LASTPIN (-12750 10350) $PN B4
J 0
(-12740 10360);
DISPLAY 0.680851 (-12740 10360);
PAINT MONO (-12740 10360);
FORCEPROP 0 LASTPIN (-12750 10250) $PN B9
J 0
(-12740 10260);
DISPLAY 0.680851 (-12740 10260);
PAINT MONO (-12740 10260);
FORCEPROP 1 LAST CLS_PN G200-13135-01
J 0
(-13750 10600);
DISPLAY 1.212766 (-13750 10600);
PAINT GREEN (-13750 10600);
FORCEPROP 1 LAST VALUE 2169890002
J 0
(-13750 10700);
DISPLAY 1.212766 (-13750 10700);
PAINT GREEN (-13750 10700);
FORCEPROP 2 LASTPIN (-12750 10050) SIG_NAME UN$524$CONNUSB14PGH4FRATH$I495$CC2
J 0
(-12740 10060);
DISPLAY 0.659574 (-12740 10060);
PAINT MONO (-12740 10060);
DISPLAY INVISIBLE (-12740 10060);
FORCEPROP 2 LASTPIN (-13850 10050) SIG_NAME UN$524$CONNUSB14PGH4FRATH$I495$CC1
J 0
(-13840 10060);
DISPLAY 0.659574 (-13840 10060);
PAINT MONO (-13840 10060);
DISPLAY INVISIBLE (-13840 10060);
FORCEPROP 1 LAST CDS_LMAN_SYM_OUTLINE 0,0,900,-1400
J 0
(-13750 10450);
DISPLAY 0.468085 (-13750 10450);
PAINT GREEN (-13750 10450);
DISPLAY INVISIBLE (-13750 10450);
FORCEPROP 1 LAST PATH I495
J 0
(-13700 10500);
DISPLAY 1.212766 (-13700 10500);
PAINT GREEN (-13700 10500);
DISPLAY INVISIBLE (-13700 10500);
FORCEPROP 2 LAST CDS_LIB connector
J 0
(-13750 10450);
DISPLAY INVISIBLE (-13750 10450);
FORCEADD GND_SG..1
R 1
(-11800 10000);
FORCEPROP 3 LASTPIN (-11850 10050) SIG_NAME SG\g
J 0
(-11840 10060);
DISPLAY 0.659574 (-11840 10060);
PAINT MONO (-11840 10060);
DISPLAY INVISIBLE (-11840 10060);
FORCEPROP 1 LAST HDL_POWER SG
R 1
J 1
(-11705 10055);
DISPLAY 0.808511 (-11705 10055);
PAINT GREEN (-11705 10055);
FORCEPROP 1 LAST BODY_TYPE PLUMBING
R 1
J 0
(-11785 10015);
DISPLAY 0.808511 (-11785 10015);
PAINT GREEN (-11785 10015);
DISPLAY INVISIBLE (-11785 10015);
FORCEPROP 1 LAST CDS_LMAN_SYM_OUTLINE 0,0,100,-50
R 1
J 0
(-11800 10000);
DISPLAY 0.468085 (-11800 10000);
PAINT GREEN (-11800 10000);
DISPLAY INVISIBLE (-11800 10000);
FORCEPROP 1 LAST PATH I496
R 1
J 0
(-11800 10035);
DISPLAY 0.808511 (-11800 10035);
PAINT GREEN (-11800 10035);
DISPLAY INVISIBLE (-11800 10035);
FORCEPROP 2 LAST CDS_LIB cls
R 1
J 0
(-11800 10000);
DISPLAY INVISIBLE (-11800 10000);
FORCEADD RESISTOR..2
R 7
(-14250 10050);
FORCEPROP 1 LAST LOCATION R442
J 2
(-14400 10100);
DISPLAY 0.978723 (-14400 10100);
PAINT GREEN (-14400 10100);
FORCEPROP 0 LAST $SEC 1
R 1
J 0
(-14150 10100);
DISPLAY 0.680851 (-14150 10100);
PAINT MONO (-14150 10100);
DISPLAY INVISIBLE (-14150 10100);
FORCEPROP 0 LAST CDS_SEC 1
R 1
J 0
(-14150 10100);
DISPLAY 1.021277 (-14150 10100);
DISPLAY INVISIBLE (-14150 10100);
FORCEPROP 0 LASTPIN (-14150 10050) $PN 1
J 2
(-14140 10060);
DISPLAY 0.680851 (-14140 10060);
PAINT MONO (-14140 10060);
FORCEPROP 0 LASTPIN (-14400 10050) $PN 2
J 0
(-14440 10060);
DISPLAY 0.680851 (-14440 10060);
PAINT MONO (-14440 10060);
FORCEPROP 1 LAST VALUE 5.1KOHM
J 2
(-13850 10100);
DISPLAY 0.978723 (-13850 10100);
PAINT GREEN (-13850 10100);
FORCEPROP 0 LAST PACKAGE 0402
J 2
(-14200 10100);
DISPLAY 0.808511 (-14200 10100);
FORCEPROP 2 LAST CDS_LIB passive
R 1
J 0
(-14250 10050);
DISPLAY INVISIBLE (-14250 10050);
FORCEPROP 1 LAST CDS_LMAN_SYM_OUTLINE -50,50,50,-100
R 1
J 0
(-14250 10050);
DISPLAY 0.468085 (-14250 10050);
PAINT GREEN (-14250 10050);
DISPLAY INVISIBLE (-14250 10050);
FORCEPROP 1 LAST TOLERANCE 1%
R 1
J 0
(-13995 9853);
DISPLAY 1.212766 (-13995 9853);
PAINT GREEN (-13995 9853);
DISPLAY INVISIBLE (-13995 9853);
FORCEPROP 1 LAST CLS_PN G155-05101-01
R 1
J 0
(-14050 9914);
DISPLAY 1.212766 (-14050 9914);
PAINT GREEN (-14050 9914);
DISPLAY INVISIBLE (-14050 9914);
FORCEPROP 1 LAST PATH I497
R 1
J 0
(-14145 9853);
DISPLAY 1.212766 (-14145 9853);
PAINT GREEN (-14145 9853);
DISPLAY INVISIBLE (-14145 9853);
FORCEADD GND_SG..1
R 7
(-14650 10000);
FORCEPROP 3 LASTPIN (-14600 10050) SIG_NAME SG\g
J 0
(-14590 10060);
DISPLAY 0.659574 (-14590 10060);
PAINT MONO (-14590 10060);
DISPLAY INVISIBLE (-14590 10060);
FORCEPROP 1 LAST HDL_POWER SG
R 1
J 1
(-14745 10055);
DISPLAY 0.808511 (-14745 10055);
PAINT GREEN (-14745 10055);
FORCEPROP 2 LAST CDS_LIB cls
J 2
(-14650 10000);
DISPLAY INVISIBLE (-14650 10000);
FORCEPROP 1 LAST PATH I498
R 1
J 0
(-14650 10035);
DISPLAY 0.808511 (-14650 10035);
PAINT GREEN (-14650 10035);
DISPLAY INVISIBLE (-14650 10035);
FORCEPROP 1 LAST CDS_LMAN_SYM_OUTLINE 0,0,100,-50
R 1
J 0
(-14650 10000);
DISPLAY 0.468085 (-14650 10000);
PAINT GREEN (-14650 10000);
DISPLAY INVISIBLE (-14650 10000);
FORCEPROP 1 LAST BODY_TYPE PLUMBING
R 1
J 0
(-14665 10015);
DISPLAY 0.808511 (-14665 10015);
PAINT GREEN (-14665 10015);
DISPLAY INVISIBLE (-14665 10015);
FORCEADD OFFPAGE_IN..2
R 2
(-8600 4400);
FORCEPROP 2 LAST $XR0 25C6<> 
J 0
(-8814 4400);
DISPLAY 0.638298 (-8814 4400);
PAINT MONO (-8814 4400);
FORCEPROP 1 LAST BODY_TYPE COMMENT
J 2
(-8610 4535);
DISPLAY 0.808511 (-8610 4535);
PAINT GREEN (-8610 4535);
DISPLAY INVISIBLE (-8610 4535);
FORCEPROP 1 LAST OFFPAGE TRUE
J 2
(-8610 4455);
DISPLAY 0.808511 (-8610 4455);
PAINT GREEN (-8610 4455);
DISPLAY INVISIBLE (-8610 4455);
FORCEPROP 1 LAST CDS_LMAN_SYM_OUTLINE -50,50,50,-50
J 2
(-8600 4400);
DISPLAY 0.468085 (-8600 4400);
PAINT GREEN (-8600 4400);
DISPLAY INVISIBLE (-8600 4400);
FORCEPROP 2 LAST CDS_LIB cls
J 0
(-8600 4400);
DISPLAY INVISIBLE (-8600 4400);
FORCEPROP 2 LAST PATH I499
J 0
(-8550 4500);
DISPLAY 1.021277 (-8550 4500);
DISPLAY INVISIBLE (-8550 4500);
FORCEADD GND_SG..1
(-10750 7200);
FORCEPROP 3 LASTPIN (-10700 7250) SIG_NAME SG\g
J 0
(-10690 7260);
DISPLAY 0.659574 (-10690 7260);
PAINT MONO (-10690 7260);
DISPLAY INVISIBLE (-10690 7260);
FORCEPROP 1 LAST HDL_POWER SG
J 1
(-10695 7105);
DISPLAY 0.808511 (-10695 7105);
PAINT GREEN (-10695 7105);
FORCEPROP 2 LAST CDS_LIB cls
J 0
(-10750 7200);
DISPLAY INVISIBLE (-10750 7200);
FORCEPROP 1 LAST CDS_LMAN_SYM_OUTLINE 0,0,100,-50
J 0
(-10750 7200);
DISPLAY 0.468085 (-10750 7200);
PAINT GREEN (-10750 7200);
DISPLAY INVISIBLE (-10750 7200);
FORCEPROP 1 LAST BODY_TYPE PLUMBING
J 0
(-10735 7185);
DISPLAY 0.808511 (-10735 7185);
PAINT GREEN (-10735 7185);
DISPLAY INVISIBLE (-10735 7185);
FORCEPROP 1 LAST PATH I5
J 0
(-10715 7200);
DISPLAY 0.808511 (-10715 7200);
PAINT GREEN (-10715 7200);
DISPLAY INVISIBLE (-10715 7200);
FORCEADD OFFPAGE_IN..2
R 2
(-2850 4100);
FORCEPROP 2 LAST $XR0 25C6<> 
J 0
(-3064 4100);
DISPLAY 0.638298 (-3064 4100);
PAINT MONO (-3064 4100);
FORCEPROP 2 LAST CDS_LIB cls
J 0
(-2850 4100);
DISPLAY INVISIBLE (-2850 4100);
FORCEPROP 2 LAST PATH I501
J 0
(-2800 4200);
DISPLAY 1.021277 (-2800 4200);
DISPLAY INVISIBLE (-2800 4200);
FORCEPROP 1 LAST CDS_LMAN_SYM_OUTLINE -50,50,50,-50
J 2
(-2850 4100);
DISPLAY 0.468085 (-2850 4100);
PAINT GREEN (-2850 4100);
DISPLAY INVISIBLE (-2850 4100);
FORCEPROP 1 LAST OFFPAGE TRUE
J 2
(-2860 4155);
DISPLAY 0.808511 (-2860 4155);
PAINT GREEN (-2860 4155);
DISPLAY INVISIBLE (-2860 4155);
FORCEPROP 1 LAST BODY_TYPE COMMENT
J 2
(-2860 4235);
DISPLAY 0.808511 (-2860 4235);
PAINT GREEN (-2860 4235);
DISPLAY INVISIBLE (-2860 4235);
FORCEADD OFFPAGE_IN..2
(-11900 4450);
FORCEPROP 2 LAST $XR0 25C6<> 
J 0
(-11845 4450);
DISPLAY 0.638298 (-11845 4450);
PAINT MONO (-11845 4450);
FORCEPROP 2 LAST CDS_LIB cls
J 0
(-11900 4450);
DISPLAY INVISIBLE (-11900 4450);
FORCEPROP 2 LAST PATH I502
J 0
(-11850 4550);
DISPLAY 1.021277 (-11850 4550);
DISPLAY INVISIBLE (-11850 4550);
FORCEPROP 1 LAST CDS_LMAN_SYM_OUTLINE -50,50,50,-50
J 0
(-11900 4450);
DISPLAY 0.468085 (-11900 4450);
PAINT GREEN (-11900 4450);
DISPLAY INVISIBLE (-11900 4450);
FORCEPROP 1 LAST BODY_TYPE COMMENT
J 0
(-11890 4585);
DISPLAY 0.808511 (-11890 4585);
PAINT GREEN (-11890 4585);
DISPLAY INVISIBLE (-11890 4585);
FORCEPROP 1 LAST OFFPAGE TRUE
J 0
(-11890 4505);
DISPLAY 0.808511 (-11890 4505);
PAINT GREEN (-11890 4505);
DISPLAY INVISIBLE (-11890 4505);
FORCEADD GND_SG..1
(-9700 7200);
FORCEPROP 3 LASTPIN (-9650 7250) SIG_NAME SG\g
J 0
(-9640 7260);
DISPLAY 0.659574 (-9640 7260);
PAINT MONO (-9640 7260);
DISPLAY INVISIBLE (-9640 7260);
FORCEPROP 1 LAST HDL_POWER SG
J 1
(-9645 7105);
DISPLAY 0.808511 (-9645 7105);
PAINT GREEN (-9645 7105);
FORCEPROP 1 LAST PATH I6
J 0
(-9665 7200);
DISPLAY 0.808511 (-9665 7200);
PAINT GREEN (-9665 7200);
DISPLAY INVISIBLE (-9665 7200);
FORCEPROP 1 LAST BODY_TYPE PLUMBING
J 0
(-9685 7185);
DISPLAY 0.808511 (-9685 7185);
PAINT GREEN (-9685 7185);
DISPLAY INVISIBLE (-9685 7185);
FORCEPROP 2 LAST CDS_LIB cls
J 0
(-9700 7200);
DISPLAY INVISIBLE (-9700 7200);
FORCEPROP 1 LAST CDS_LMAN_SYM_OUTLINE 0,0,100,-50
J 0
(-9700 7200);
DISPLAY 0.468085 (-9700 7200);
PAINT GREEN (-9700 7200);
DISPLAY INVISIBLE (-9700 7200);
FORCEADD FT4232HL_REEL_QFP64..1
(-7900 11550);
FORCEPROP 1 LAST $LOCATION U18
J 0
(-7900 11600);
DISPLAY 1.212766 (-7900 11600);
PAINT GREEN (-7900 11600);
FORCEPROP 0 LAST CDS_LOCATION U18
J 0
(-7900 11600);
DISPLAY 1.212766 (-7900 11600);
PAINT GREEN (-7900 11600);
DISPLAY INVISIBLE (-7900 11600);
FORCEPROP 0 LAST $SEC 1
J 0
(-7900 11900);
DISPLAY 0.680851 (-7900 11900);
PAINT MONO (-7900 11900);
DISPLAY INVISIBLE (-7900 11900);
FORCEPROP 0 LAST CDS_SEC 1
J 0
(-7900 11900);
DISPLAY 1.021277 (-7900 11900);
DISPLAY INVISIBLE (-7900 11900);
FORCEPROP 0 LASTPIN (-6800 11450) $PN 16
J 0
(-6790 11460);
DISPLAY 0.680851 (-6790 11460);
PAINT MONO (-6790 11460);
FORCEPROP 0 LASTPIN (-6800 11350) $PN 17
J 0
(-6790 11360);
DISPLAY 0.680851 (-6790 11360);
PAINT MONO (-6790 11360);
FORCEPROP 0 LASTPIN (-6800 11250) $PN 18
J 0
(-6790 11260);
DISPLAY 0.680851 (-6790 11260);
PAINT MONO (-6790 11260);
FORCEPROP 0 LASTPIN (-6800 11150) $PN 19
J 0
(-6790 11160);
DISPLAY 0.680851 (-6790 11160);
PAINT MONO (-6790 11160);
FORCEPROP 0 LASTPIN (-6800 11050) $PN 21
J 0
(-6790 11060);
DISPLAY 0.680851 (-6790 11060);
PAINT MONO (-6790 11060);
FORCEPROP 0 LASTPIN (-6800 10950) $PN 22
J 0
(-6790 10960);
DISPLAY 0.680851 (-6790 10960);
PAINT MONO (-6790 10960);
FORCEPROP 0 LASTPIN (-6800 10850) $PN 23
J 0
(-6790 10860);
DISPLAY 0.680851 (-6790 10860);
PAINT MONO (-6790 10860);
FORCEPROP 0 LASTPIN (-6800 10750) $PN 24
J 0
(-6790 10760);
DISPLAY 0.680851 (-6790 10760);
PAINT MONO (-6790 10760);
FORCEPROP 0 LASTPIN (-6800 7550) $PN 10
J 0
(-6790 7560);
DISPLAY 0.680851 (-6790 7560);
PAINT MONO (-6790 7560);
FORCEPROP 0 LASTPIN (-6800 10550) $PN 26
J 0
(-6790 10560);
DISPLAY 0.680851 (-6790 10560);
PAINT MONO (-6790 10560);
FORCEPROP 0 LASTPIN (-6800 10450) $PN 27
J 0
(-6790 10460);
DISPLAY 0.680851 (-6790 10460);
PAINT MONO (-6790 10460);
FORCEPROP 0 LASTPIN (-6800 10350) $PN 28
J 0
(-6790 10360);
DISPLAY 0.680851 (-6790 10360);
PAINT MONO (-6790 10360);
FORCEPROP 0 LASTPIN (-6800 10250) $PN 29
J 0
(-6790 10260);
DISPLAY 0.680851 (-6790 10260);
PAINT MONO (-6790 10260);
FORCEPROP 0 LASTPIN (-6800 10150) $PN 30
J 0
(-6790 10160);
DISPLAY 0.680851 (-6790 10160);
PAINT MONO (-6790 10160);
FORCEPROP 0 LASTPIN (-6800 10050) $PN 32
J 0
(-6790 10060);
DISPLAY 0.680851 (-6790 10060);
PAINT MONO (-6790 10060);
FORCEPROP 0 LASTPIN (-6800 9950) $PN 33
J 0
(-6790 9960);
DISPLAY 0.680851 (-6790 9960);
PAINT MONO (-6790 9960);
FORCEPROP 0 LASTPIN (-6800 9850) $PN 34
J 0
(-6790 9860);
DISPLAY 0.680851 (-6790 9860);
PAINT MONO (-6790 9860);
FORCEPROP 0 LASTPIN (-6800 9650) $PN 38
J 0
(-6790 9660);
DISPLAY 0.680851 (-6790 9660);
PAINT MONO (-6790 9660);
FORCEPROP 0 LASTPIN (-6800 9550) $PN 39
J 0
(-6790 9560);
DISPLAY 0.680851 (-6790 9560);
PAINT MONO (-6790 9560);
FORCEPROP 0 LASTPIN (-6800 9450) $PN 40
J 0
(-6790 9460);
DISPLAY 0.680851 (-6790 9460);
PAINT MONO (-6790 9460);
FORCEPROP 0 LASTPIN (-6800 9350) $PN 41
J 0
(-6790 9360);
DISPLAY 0.680851 (-6790 9360);
PAINT MONO (-6790 9360);
FORCEPROP 0 LASTPIN (-6800 9250) $PN 43
J 0
(-6790 9260);
DISPLAY 0.680851 (-6790 9260);
PAINT MONO (-6790 9260);
FORCEPROP 0 LASTPIN (-6800 9150) $PN 44
J 0
(-6790 9160);
DISPLAY 0.680851 (-6790 9160);
PAINT MONO (-6790 9160);
FORCEPROP 0 LASTPIN (-6800 9050) $PN 45
J 0
(-6790 9060);
DISPLAY 0.680851 (-6790 9060);
PAINT MONO (-6790 9060);
FORCEPROP 0 LASTPIN (-6800 8950) $PN 46
J 0
(-6790 8960);
DISPLAY 0.680851 (-6790 8960);
PAINT MONO (-6790 8960);
FORCEPROP 0 LASTPIN (-6800 8750) $PN 48
J 0
(-6790 8760);
DISPLAY 0.680851 (-6790 8760);
PAINT MONO (-6790 8760);
FORCEPROP 0 LASTPIN (-6800 8650) $PN 52
J 0
(-6790 8660);
DISPLAY 0.680851 (-6790 8660);
PAINT MONO (-6790 8660);
FORCEPROP 0 LASTPIN (-6800 8550) $PN 53
J 0
(-6790 8560);
DISPLAY 0.680851 (-6790 8560);
PAINT MONO (-6790 8560);
FORCEPROP 0 LASTPIN (-6800 8450) $PN 54
J 0
(-6790 8460);
DISPLAY 0.680851 (-6790 8460);
PAINT MONO (-6790 8460);
FORCEPROP 0 LASTPIN (-6800 8350) $PN 55
J 0
(-6790 8360);
DISPLAY 0.680851 (-6790 8360);
PAINT MONO (-6790 8360);
FORCEPROP 0 LASTPIN (-6800 8250) $PN 57
J 0
(-6790 8260);
DISPLAY 0.680851 (-6790 8260);
PAINT MONO (-6790 8260);
FORCEPROP 0 LASTPIN (-6800 8150) $PN 58
J 0
(-6790 8160);
DISPLAY 0.680851 (-6790 8160);
PAINT MONO (-6790 8160);
FORCEPROP 0 LASTPIN (-6800 8050) $PN 59
J 0
(-6790 8060);
DISPLAY 0.680851 (-6790 8060);
PAINT MONO (-6790 8060);
FORCEPROP 0 LASTPIN (-8000 9850) $PN 7
J 2
(-8010 9860);
DISPLAY 0.680851 (-8010 9860);
PAINT MONO (-8010 9860);
FORCEPROP 0 LASTPIN (-8000 9750) $PN 8
J 2
(-8010 9760);
DISPLAY 0.680851 (-8010 9760);
PAINT MONO (-8010 9760);
FORCEPROP 0 LASTPIN (-8000 9050) $PN 62
J 2
(-8010 9060);
DISPLAY 0.680851 (-8010 9060);
PAINT MONO (-8010 9060);
FORCEPROP 0 LASTPIN (-8000 9150) $PN 63
J 2
(-8010 9160);
DISPLAY 0.680851 (-8010 9160);
PAINT MONO (-8010 9160);
FORCEPROP 0 LASTPIN (-8000 8950) $PN 61
J 2
(-8010 8960);
DISPLAY 0.680851 (-8010 8960);
PAINT MONO (-8010 8960);
FORCEPROP 0 LASTPIN (-6800 7350) $PN 51
J 0
(-6790 7360);
DISPLAY 0.680851 (-6790 7360);
PAINT MONO (-6790 7360);
FORCEPROP 0 LASTPIN (-6800 7250) $PN 47
J 0
(-6790 7260);
DISPLAY 0.680851 (-6790 7260);
PAINT MONO (-6790 7260);
FORCEPROP 0 LASTPIN (-6800 7150) $PN 35
J 0
(-6790 7160);
DISPLAY 0.680851 (-6790 7160);
PAINT MONO (-6790 7160);
FORCEPROP 0 LASTPIN (-6800 7050) $PN 25
J 0
(-6790 7060);
DISPLAY 0.680851 (-6790 7060);
PAINT MONO (-6790 7060);
FORCEPROP 0 LASTPIN (-6800 6950) $PN 15
J 0
(-6790 6960);
DISPLAY 0.680851 (-6790 6960);
PAINT MONO (-6790 6960);
FORCEPROP 0 LASTPIN (-6800 6850) $PN 11
J 0
(-6790 6860);
DISPLAY 0.680851 (-6790 6860);
PAINT MONO (-6790 6860);
FORCEPROP 0 LASTPIN (-6800 6750) $PN 5
J 0
(-6790 6760);
DISPLAY 0.680851 (-6790 6760);
PAINT MONO (-6790 6760);
FORCEPROP 0 LASTPIN (-6800 6650) $PN 1
J 0
(-6790 6660);
DISPLAY 0.680851 (-6790 6660);
PAINT MONO (-6790 6660);
FORCEPROP 0 LASTPIN (-8000 8750) $PN 2
J 2
(-8010 8760);
DISPLAY 0.680851 (-8010 8760);
PAINT MONO (-8010 8760);
FORCEPROP 0 LASTPIN (-8000 8550) $PN 3
J 2
(-8010 8560);
DISPLAY 0.680851 (-8010 8560);
PAINT MONO (-8010 8560);
FORCEPROP 0 LASTPIN (-6800 7850) $PN 60
J 0
(-6790 7860);
DISPLAY 0.680851 (-6790 7860);
PAINT MONO (-6790 7860);
FORCEPROP 0 LASTPIN (-8000 9550) $PN 6
J 2
(-8010 9560);
DISPLAY 0.680851 (-8010 9560);
PAINT MONO (-8010 9560);
FORCEPROP 0 LASTPIN (-8000 9350) $PN 14
J 2
(-8010 9360);
DISPLAY 0.680851 (-8010 9360);
PAINT MONO (-8010 9360);
FORCEPROP 0 LASTPIN (-6800 7750) $PN 36
J 0
(-6790 7760);
DISPLAY 0.680851 (-6790 7760);
PAINT MONO (-6790 7760);
FORCEPROP 0 LASTPIN (-8000 8350) $PN 13
J 2
(-8010 8360);
DISPLAY 0.680851 (-8010 8360);
PAINT MONO (-8010 8360);
FORCEPROP 0 LASTPIN (-8000 11450) $PN 56
J 2
(-8010 11460);
DISPLAY 0.680851 (-8010 11460);
PAINT MONO (-8010 11460);
FORCEPROP 0 LASTPIN (-8000 11350) $PN 42
J 2
(-8010 11360);
DISPLAY 0.680851 (-8010 11360);
PAINT MONO (-8010 11360);
FORCEPROP 0 LASTPIN (-8000 11250) $PN 31
J 2
(-8010 11260);
DISPLAY 0.680851 (-8010 11260);
PAINT MONO (-8010 11260);
FORCEPROP 0 LASTPIN (-8000 11150) $PN 20
J 2
(-8010 11160);
DISPLAY 0.680851 (-8010 11160);
PAINT MONO (-8010 11160);
FORCEPROP 0 LASTPIN (-8000 10950) $PN 64
J 2
(-8010 10960);
DISPLAY 0.680851 (-8010 10960);
PAINT MONO (-8010 10960);
FORCEPROP 0 LASTPIN (-8000 10850) $PN 37
J 2
(-8010 10860);
DISPLAY 0.680851 (-8010 10860);
PAINT MONO (-8010 10860);
FORCEPROP 0 LASTPIN (-8000 10750) $PN 12
J 2
(-8010 10760);
DISPLAY 0.680851 (-8010 10760);
PAINT MONO (-8010 10760);
FORCEPROP 0 LASTPIN (-8000 10450) $PN 4
J 2
(-8010 10460);
DISPLAY 0.680851 (-8010 10460);
PAINT MONO (-8010 10460);
FORCEPROP 0 LASTPIN (-8000 10550) $PN 9
J 2
(-8010 10560);
DISPLAY 0.680851 (-8010 10560);
PAINT MONO (-8010 10560);
FORCEPROP 0 LASTPIN (-8000 10250) $PN 50
J 2
(-8010 10260);
DISPLAY 0.680851 (-8010 10260);
PAINT MONO (-8010 10260);
FORCEPROP 0 LASTPIN (-8000 10050) $PN 49
J 2
(-8010 10060);
DISPLAY 0.680851 (-8010 10060);
PAINT MONO (-8010 10060);
FORCEPROP 1 LAST VALUE FT4232HL-REEL
J 0
(-7900 11800);
DISPLAY 1.212766 (-7900 11800);
PAINT GREEN (-7900 11800);
FORCEPROP 1 LAST CLS_PN G223-10282-01
J 0
(-7900 11700);
DISPLAY 1.212766 (-7900 11700);
PAINT GREEN (-7900 11700);
FORCEPROP 1 LAST PATH I64
J 0
(-7850 11600);
DISPLAY 1.212766 (-7850 11600);
PAINT GREEN (-7850 11600);
DISPLAY INVISIBLE (-7850 11600);
FORCEPROP 2 LASTPIN (-8000 9350) SIG_NAME UN$524$FT4232HLREELQFP64$I64$RESET
J 0
(-7990 9360);
DISPLAY 0.659574 (-7990 9360);
PAINT MONO (-7990 9360);
DISPLAY INVISIBLE (-7990 9360);
FORCEPROP 2 LASTPIN (-8000 9550) SIG_NAME UN$524$FT4232HLREELQFP64$I64$REF
J 0
(-7990 9560);
DISPLAY 0.659574 (-7990 9560);
PAINT MONO (-7990 9560);
DISPLAY INVISIBLE (-7990 9560);
FORCEPROP 1 LAST CDS_LMAN_SYM_OUTLINE 0,0,1000,-5000
J 0
(-7900 11550);
DISPLAY 0.468085 (-7900 11550);
PAINT GREEN (-7900 11550);
DISPLAY INVISIBLE (-7900 11550);
FORCEPROP 2 LAST CDS_LIB interface
J 0
(-7900 11550);
DISPLAY INVISIBLE (-7900 11550);
FORCEPROP 2 LASTPIN (-6800 9950) SIG_NAME UN$524$FT4232HLREELQFP64$I64$BDBUS6
J 0
(-6790 9960);
DISPLAY 0.659574 (-6790 9960);
PAINT MONO (-6790 9960);
DISPLAY INVISIBLE (-6790 9960);
FORCEPROP 2 LASTPIN (-6800 9850) SIG_NAME UN$524$FT4232HLREELQFP64$I64$BDBUS7
J 0
(-6790 9860);
DISPLAY 0.659574 (-6790 9860);
PAINT MONO (-6790 9860);
DISPLAY INVISIBLE (-6790 9860);
FORCEPROP 2 LASTPIN (-6800 10250) SIG_NAME UN$524$FT4232HLREELQFP64$I64$BDBUS3
J 0
(-6790 10260);
DISPLAY 0.659574 (-6790 10260);
PAINT MONO (-6790 10260);
DISPLAY INVISIBLE (-6790 10260);
FORCEPROP 2 LASTPIN (-6800 10150) SIG_NAME UN$524$FT4232HLREELQFP64$I64$BDBUS4
J 0
(-6790 10160);
DISPLAY 0.659574 (-6790 10160);
PAINT MONO (-6790 10160);
DISPLAY INVISIBLE (-6790 10160);
FORCEPROP 2 LASTPIN (-6800 10050) SIG_NAME UN$524$FT4232HLREELQFP64$I64$BDBUS5
J 0
(-6790 10060);
DISPLAY 0.659574 (-6790 10060);
PAINT MONO (-6790 10060);
DISPLAY INVISIBLE (-6790 10060);
FORCEPROP 2 LASTPIN (-6800 10750) SIG_NAME UN$524$FT4232HLREELQFP64$I64$ADBUS7
J 0
(-6790 10760);
DISPLAY 0.659574 (-6790 10760);
PAINT MONO (-6790 10760);
DISPLAY INVISIBLE (-6790 10760);
FORCEADD CAPACITOR..1
R 1
(-10700 7400);
FORCEPROP 1 LAST $LOCATION C86
J 2
(-10450 7250);
DISPLAY 1.212766 (-10450 7250);
PAINT GREEN (-10450 7250);
FORCEPROP 0 LAST CDS_LOCATION C86
R 1
J 0
(-10600 7550);
DISPLAY 1.021277 (-10600 7550);
DISPLAY INVISIBLE (-10600 7550);
FORCEPROP 0 LAST $SEC 1
R 1
J 0
(-10600 7550);
DISPLAY 0.680851 (-10600 7550);
PAINT MONO (-10600 7550);
DISPLAY INVISIBLE (-10600 7550);
FORCEPROP 0 LAST CDS_SEC 1
R 1
J 0
(-10600 7550);
DISPLAY 1.021277 (-10600 7550);
DISPLAY INVISIBLE (-10600 7550);
FORCEPROP 0 LASTPIN (-10700 7300) $PN 1
R 1
J 2
(-10710 7290);
DISPLAY 0.680851 (-10710 7290);
PAINT MONO (-10710 7290);
FORCEPROP 0 LASTPIN (-10700 7550) $PN 2
R 1
J 0
(-10710 7560);
DISPLAY 0.680851 (-10710 7560);
PAINT MONO (-10710 7560);
FORCEPROP 0 LAST PACKAGE 0201
J 0
(-10550 7450);
DISPLAY 1.021277 (-10550 7450);
FORCEPROP 1 LAST VALUE 18PF
J 0
(-10600 7350);
DISPLAY 1.212766 (-10600 7350);
PAINT GREEN (-10600 7350);
FORCEPROP 1 LAST CLS_PN G104-0A180-FJ
R 1
J 2
(-10800 7350);
DISPLAY 1.212766 (-10800 7350);
PAINT GREEN (-10800 7350);
DISPLAY INVISIBLE (-10800 7350);
FORCEPROP 2 LAST CDS_LIB passive
J 0
(-10700 7400);
DISPLAY INVISIBLE (-10700 7400);
FORCEPROP 1 LAST CDS_LMAN_SYM_OUTLINE 0,50,50,-50
R 1
J 0
(-10700 7400);
DISPLAY 0.468085 (-10700 7400);
PAINT GREEN (-10700 7400);
DISPLAY INVISIBLE (-10700 7400);
FORCEPROP 1 LAST TOLERANCE 5%
R 1
J 2
(-10800 7300);
DISPLAY 1.212766 (-10800 7300);
PAINT GREEN (-10800 7300);
DISPLAY INVISIBLE (-10800 7300);
FORCEPROP 2 LASTPIN (-10700 7550) SIG_NAME UN$524$CAPACITOR$I7$2
J 0
(-10690 7560);
DISPLAY 0.659574 (-10690 7560);
PAINT MONO (-10690 7560);
DISPLAY INVISIBLE (-10690 7560);
FORCEPROP 1 LAST PATH I7
R 1
J 2
(-10800 7350);
DISPLAY 1.212766 (-10800 7350);
PAINT GREEN (-10800 7350);
DISPLAY INVISIBLE (-10800 7350);
FORCEADD XTAL_4..1
(-10500 8050);
FORCEPROP 1 LAST $LOCATION Y2
J 0
(-10450 8200);
DISPLAY 1.212766 (-10450 8200);
PAINT GREEN (-10450 8200);
FORCEPROP 0 LAST CDS_LOCATION Y2
J 0
(-10450 8450);
DISPLAY 1.021277 (-10450 8450);
DISPLAY INVISIBLE (-10450 8450);
FORCEPROP 0 LAST $SEC 1
J 0
(-10450 8450);
DISPLAY 0.680851 (-10450 8450);
PAINT MONO (-10450 8450);
DISPLAY INVISIBLE (-10450 8450);
FORCEPROP 0 LAST CDS_SEC 1
J 0
(-10450 8450);
DISPLAY 1.021277 (-10450 8450);
DISPLAY INVISIBLE (-10450 8450);
FORCEPROP 0 LASTPIN (-10600 7650) $PN 1
J 2
(-10610 7660);
DISPLAY 0.680851 (-10610 7660);
PAINT MONO (-10610 7660);
FORCEPROP 0 LASTPIN (-9900 7650) $PN 2
J 0
(-9890 7660);
DISPLAY 0.680851 (-9890 7660);
PAINT MONO (-9890 7660);
FORCEPROP 0 LASTPIN (-9900 7950) $PN 3
J 0
(-9890 7960);
DISPLAY 0.680851 (-9890 7960);
PAINT MONO (-9890 7960);
FORCEPROP 0 LASTPIN (-10600 7950) $PN 4
J 2
(-10610 7960);
DISPLAY 0.680851 (-10610 7960);
PAINT MONO (-10610 7960);
FORCEPROP 0 LAST PART_NUMBER 7M12000031
J 0
(-10250 8200);
DISPLAY 1.021277 (-10250 8200);
FORCEPROP 1 LAST CLS_PN G131-10038-02
J 0
(-10450 8300);
DISPLAY 1.212766 (-10450 8300);
PAINT GREEN (-10450 8300);
FORCEPROP 1 LAST CDS_LMAN_SYM_OUTLINE 0,0,500,-500
J 0
(-10500 8050);
DISPLAY 0.468085 (-10500 8050);
PAINT GREEN (-10500 8050);
DISPLAY INVISIBLE (-10500 8050);
FORCEPROP 2 LAST CDS_LIB clock
J 0
(-10500 8050);
DISPLAY INVISIBLE (-10500 8050);
FORCEPROP 1 LAST PATH I8
J 0
(-10450 8300);
DISPLAY 1.212766 (-10450 8300);
PAINT GREEN (-10450 8300);
DISPLAY INVISIBLE (-10450 8300);
FORCEADD GND_SG..1
(-10900 7800);
FORCEPROP 3 LASTPIN (-10850 7850) SIG_NAME SG\g
J 0
(-10840 7860);
DISPLAY 0.659574 (-10840 7860);
PAINT MONO (-10840 7860);
DISPLAY INVISIBLE (-10840 7860);
FORCEPROP 1 LAST HDL_POWER SG
J 1
(-10845 7705);
DISPLAY 0.808511 (-10845 7705);
PAINT GREEN (-10845 7705);
FORCEPROP 1 LAST PATH I9
J 0
(-10865 7800);
DISPLAY 0.808511 (-10865 7800);
PAINT GREEN (-10865 7800);
DISPLAY INVISIBLE (-10865 7800);
FORCEPROP 1 LAST BODY_TYPE PLUMBING
J 0
(-10885 7785);
DISPLAY 0.808511 (-10885 7785);
PAINT GREEN (-10885 7785);
DISPLAY INVISIBLE (-10885 7785);
FORCEPROP 1 LAST CDS_LMAN_SYM_OUTLINE 0,0,100,-50
J 0
(-10900 7800);
DISPLAY 0.468085 (-10900 7800);
PAINT GREEN (-10900 7800);
DISPLAY INVISIBLE (-10900 7800);
FORCEPROP 2 LAST CDS_LIB cls
J 0
(-10900 7800);
DISPLAY INVISIBLE (-10900 7800);
FORCEADD GND_SG..1
(-6650 6550);
FORCEPROP 3 LASTPIN (-6600 6600) SIG_NAME SG\g
J 0
(-6590 6610);
DISPLAY 0.659574 (-6590 6610);
PAINT MONO (-6590 6610);
DISPLAY INVISIBLE (-6590 6610);
FORCEPROP 1 LAST HDL_POWER SG
J 1
(-6595 6455);
DISPLAY 0.808511 (-6595 6455);
PAINT GREEN (-6595 6455);
FORCEPROP 1 LAST PATH I95
J 0
(-6615 6550);
DISPLAY 0.808511 (-6615 6550);
PAINT GREEN (-6615 6550);
DISPLAY INVISIBLE (-6615 6550);
FORCEPROP 1 LAST BODY_TYPE PLUMBING
J 0
(-6635 6535);
DISPLAY 0.808511 (-6635 6535);
PAINT GREEN (-6635 6535);
DISPLAY INVISIBLE (-6635 6535);
FORCEPROP 2 LAST CDS_LIB cls
J 0
(-6650 6550);
DISPLAY INVISIBLE (-6650 6550);
FORCEPROP 1 LAST CDS_LMAN_SYM_OUTLINE 0,0,100,-50
J 0
(-6650 6550);
DISPLAY 0.468085 (-6650 6550);
PAINT GREEN (-6650 6550);
DISPLAY INVISIBLE (-6650 6550);
FORCEADD SHEET_A1..1
(400 1750);
FORCEPROP 2 LAST CUSTOM_TXT_CDS <XR_PAGE_TITLE>
J 0
(-15170 13100);
DISPLAY 0.638298 (-15170 13100);
PAINT PINK (-15170 13100);
FORCEPROP 1 LAST CUSTOM_TXT_CDS <DOCNO>
J 0
(-1650 2135);
DISPLAY 0.978723 (-1650 2135);
FORCEPROP 1 LAST CUSTOM_TXT_CDS <CON_PAGE_NUM>
J 0
(-1755 1800);
DISPLAY 0.978723 (-1755 1800);
FORCEPROP 1 LAST CUSTOM_TXT_CDS <DATE>
J 0
(-300 1925);
DISPLAY 0.978723 (-300 1925);
FORCEPROP 1 LAST CUSTOM_TXT_CDS <TITLE>
J 1
(-1385 2380);
DISPLAY 0.978723 (-1385 2380);
FORCEPROP 1 LAST CUSTOM_TXT_CDS <DESIGNER>
J 0
(-300 2350);
DISPLAY 0.978723 (-300 2350);
FORCEPROP 1 LAST CUSTOM_TXT_CDS <CON_TOTAL_PAGES>
J 0
(-1445 1800);
DISPLAY 0.808511 (-1445 1800);
FORCEPROP 1 LAST CUSTOM_TXT_CDS <ASSY_PN>
J 0
(-1650 1925);
DISPLAY 0.978723 (-1650 1925);
FORCEPROP 1 LAST CUSTOM_TXT_CDS <DOCREV>
J 0
(-300 2125);
DISPLAY 0.978723 (-300 2125);
FORCEPROP 1 LAST TITLE USB2UART/MPSSE
J 0
(-2100 2600);
DISPLAY 3.042553 (-2100 2600);
PAINT GREEN (-2100 2600);
FORCEPROP 1 LAST COMMENT_BODY TRUE
J 0
(410 1805);
DISPLAY 0.808511 (410 1805);
DISPLAY INVISIBLE (410 1805);
FORCEPROP 2 LAST CDS_LIB cls
J 0
(400 1750);
DISPLAY INVISIBLE (400 1750);
FORCEPROP 1 LAST CDS_LMAN_SYM_OUTLINE -15850,11500,200,-200
J 0
(400 1750);
DISPLAY 0.468085 (400 1750);
PAINT GREEN (400 1750);
DISPLAY INVISIBLE (400 1750);
FORCEPROP 2 LAST PAGE_BORDER TRUE
J 0
(-15170 13100);
DISPLAY 0.638298 (-15170 13100);
PAINT PINK (-15170 13100);
DISPLAY INVISIBLE (-15170 13100);
FORCEPROP 2 LAST CDS_XR_PAGE_TITLE CR-24 : @TIMECARD_LIB.TIMECARD(SCH_1):PAGE24
J 0
(-15170 13100);
DISPLAY 0.638298 (-15170 13100);
PAINT PINK (-15170 13100);
DISPLAY INVISIBLE (-15170 13100);
WIRE 16 -1 (-10850 7950)(-10600 7950);
WIRE 16 -1 (-10850 7950)(-10850 7850);
WIRE 16 -1 (-10700 7250)(-10700 7300);
WIRE 16 -1 (-14400 10050)(-14600 10050);
WIRE 16 -1 (-12200 10050)(-11850 10050);
WIRE 16 -1 (-3250 3850)(-3600 3850);
WIRE 16 -1 (-3600 3850)(-3600 3950);
WIRE 16 -1 (-8900 4200)(-9250 4200);
WIRE 16 -1 (-9250 4200)(-9250 4250);
WIRE 16 -1 (-4500 11600)(-4500 11700);
WIRE 16 -1 (-4500 11600)(-5150 11600);
WIRE 16 -1 (-2750 7950)(-3000 7950);
WIRE 16 -1 (-3000 7950)(-3000 7850);
WIRE 16 -1 (-6600 6650)(-6600 6750);
WIRE 16 -1 (-6600 6600)(-6600 6650);
WIRE 16 -1 (-6800 6650)(-6600 6650);
WIRE 16 -1 (-6600 6750)(-6600 6850);
WIRE 16 -1 (-6800 6750)(-6600 6750);
WIRE 16 -1 (-6600 6850)(-6600 6950);
WIRE 16 -1 (-6800 6850)(-6600 6850);
WIRE 16 -1 (-6600 6950)(-6600 7050);
WIRE 16 -1 (-6800 6950)(-6600 6950);
WIRE 16 -1 (-6600 7050)(-6600 7150);
WIRE 16 -1 (-6800 7050)(-6600 7050);
WIRE 16 -1 (-6600 7150)(-6600 7250);
WIRE 16 -1 (-6800 7150)(-6600 7150);
WIRE 16 -1 (-6600 7250)(-6600 7350);
WIRE 16 -1 (-6800 7250)(-6600 7250);
WIRE 16 -1 (-6600 7350)(-6600 7550);
WIRE 16 -1 (-6800 7350)(-6600 7350);
WIRE 16 -1 (-6600 7550)(-6800 7550);
WIRE 16 -1 (-9850 7650)(-9850 7350);
WIRE 16 -1 (-9850 7650)(-9900 7650);
WIRE 16 -1 (-9650 7350)(-9850 7350);
WIRE 16 -1 (-9650 7500)(-9650 7350);
WIRE 16 -1 (-9650 7350)(-9650 7250);
WIRE 16 -1 (-4350 2400)(-4350 2100);
WIRE 16 -1 (-4350 2100)(-4800 2100);
WIRE 16 -1 (-4800 2150)(-4800 2100);
WIRE 16 -1 (-4800 2100)(-4800 2050);
WIRE 16 -1 (-4350 2650)(-4350 2900);
WIRE 16 -1 (-4350 2900)(-4800 2900);
WIRE 16 -1 (-4800 2900)(-4800 2950);
WIRE 16 -1 (-4800 2850)(-4800 2900);
WIRE 16 -1 (-3000 2400)(-3000 2100);
WIRE 16 -1 (-3000 2100)(-3450 2100);
WIRE 16 -1 (-3450 2150)(-3450 2100);
WIRE 16 -1 (-3450 2100)(-3450 2050);
WIRE 16 -1 (-3000 2650)(-3000 2900);
WIRE 16 -1 (-3000 2900)(-3450 2900);
WIRE 16 -1 (-3450 2850)(-3450 2900);
WIRE 16 -1 (-3450 2900)(-3450 2950);
WIRE 16 -1 (-10650 2400)(-10650 2100);
WIRE 16 -1 (-10650 2100)(-11100 2100);
WIRE 16 -1 (-11100 2150)(-11100 2100);
WIRE 16 -1 (-11100 2100)(-11100 2050);
WIRE 16 -1 (-13200 2400)(-13200 2100);
WIRE 16 -1 (-13200 2100)(-13650 2100);
WIRE 16 -1 (-13650 2150)(-13650 2100);
WIRE 16 -1 (-13650 2100)(-13650 2050);
WIRE 16 -1 (-13200 2650)(-13200 2900);
WIRE 16 -1 (-13200 2900)(-12350 2900);
WIRE 16 -1 (-13200 2900)(-13650 2900);
WIRE 16 -1 (-13650 2850)(-13650 2900);
WIRE 16 -1 (-13650 2900)(-13650 2950);
WIRE 16 -1 (-12350 2900)(-11900 2900);
WIRE 16 -1 (-12350 2850)(-12350 2900);
WIRE 16 -1 (-11900 2900)(-11100 2900);
WIRE 16 -1 (-11900 2650)(-11900 2900);
WIRE 16 -1 (-11100 2900)(-10650 2900);
WIRE 16 -1 (-11100 2850)(-11100 2900);
WIRE 16 -1 (-10650 2650)(-10650 2900);
WIRE 16 -1 (-11900 2400)(-11900 2100);
WIRE 16 -1 (-11900 2100)(-12350 2100);
WIRE 16 -1 (-12350 2150)(-12350 2100);
WIRE 16 -1 (-12350 2100)(-12350 2050);
WIRE 16 -1 (-4950 5250)(-4600 5250);
WIRE 16 -1 (-4950 5550)(-4950 5250);
WIRE 16 -1 (-4950 5250)(-4950 4950);
WIRE 16 -1 (-4950 4950)(-4600 4950);
WIRE 16 -1 (-4950 4950)(-4950 4650);
WIRE 16 -1 (-4600 5550)(-4950 5550);
WIRE 16 -1 (-4950 5550)(-4950 5700);
WIRE 16 -1 (-4950 4650)(-4600 4650);
WIRE 16 -1 (-3250 3650)(-3600 3650);
WIRE 16 -1 (-3600 3750)(-3600 3650);
WIRE 16 -1 (-3600 3550)(-3600 3650);
WIRE 16 -1 (-3250 3750)(-3600 3750);
WIRE 16 -1 (-12650 3900)(-12750 3900);
WIRE 16 -1 (-12650 3800)(-12650 3900);
WIRE 16 -1 (-11300 9350)(-9700 9350);
WIRE 16 -1 (-11300 9350)(-11300 9600);
WIRE 16 -1 (-11300 9900)(-11300 9600);
WIRE 16 -1 (-11300 9600)(-11700 9600);
WIRE 16 -1 (-11700 9250)(-11700 9600);
WIRE 16 -1 (-12200 9600)(-11700 9600);
WIRE 16 -1 (-12200 9600)(-12200 9450);
WIRE 16 -1 (-11850 3900)(-11350 3900);
WIRE 16 -1 (-11350 4100)(-11350 3900);
WIRE 16 -1 (-11350 3800)(-11350 3900);
WIRE 16 -1 (-11850 4100)(-11350 4100);
WIRE 16 -1 (-11850 4200)(-11300 4200);
WIRE 16 -1 (-11300 4250)(-11300 4200);
WIRE 16 -1 (-11300 4000)(-11300 4200);
WIRE 16 -1 (-11850 4000)(-11300 4000);
WIRE 16 -1 (-8900 4000)(-9200 4000);
WIRE 16 -1 (-9200 4000)(-9200 4100);
WIRE 16 -1 (-9200 3950)(-9200 4000);
WIRE 16 -1 (-8900 4100)(-9200 4100);
WIRE 16 -1 (-13850 10350)(-14000 10350);
WIRE 16 -1 (-14000 10350)(-14000 10250);
WIRE 16 -1 (-14000 10350)(-14150 10350);
WIRE 16 -1 (-14150 10750)(-14150 10350);
WIRE 16 -1 (-13850 10250)(-14000 10250);
WIRE 16 -1 (-12600 9150)(-12600 8900);
WIRE 16 -1 (-12600 9150)(-12600 9250);
WIRE 16 -1 (-12750 9150)(-12600 9150);
WIRE 16 -1 (-12600 8900)(-14000 8900);
WIRE 16 -1 (-14000 8900)(-14000 9150);
WIRE 16 -1 (-14000 8800)(-14000 8900);
WIRE 16 -1 (-12600 9450)(-12600 9250);
WIRE 16 -1 (-12750 9250)(-12600 9250);
WIRE 16 -1 (-12600 9550)(-12600 9450);
WIRE 16 -1 (-12750 9450)(-12600 9450);
WIRE 16 -1 (-14000 9150)(-14000 9250);
WIRE 16 -1 (-14000 9150)(-13850 9150);
WIRE 16 -1 (-13850 9250)(-14000 9250);
WIRE 16 -1 (-14000 9450)(-14000 9250);
WIRE 16 -1 (-12750 9550)(-12600 9550);
WIRE 16 -1 (-14000 9450)(-14000 9550);
WIRE 16 -1 (-14000 9450)(-13850 9450);
WIRE 16 -1 (-14000 9550)(-13850 9550);
WIRE 16 -1 (-12600 10350)(-12550 10350);
WIRE 16 -1 (-12600 10350)(-12600 10250);
WIRE 16 -1 (-12750 10350)(-12600 10350);
WIRE 16 -1 (-12550 10750)(-12550 10350);
WIRE 16 -1 (-12600 10250)(-12750 10250);
WIRE 16 -1 (-8000 11450)(-8200 11450);
WIRE 16 -1 (-8200 11900)(-8200 11450);
WIRE 16 -1 (-8200 11450)(-8200 11350);
WIRE 16 -1 (-8000 11350)(-8200 11350);
WIRE 16 -1 (-8200 11350)(-8200 11250);
WIRE 16 -1 (-8200 11250)(-8000 11250);
WIRE 16 -1 (-8200 11250)(-8200 11150);
WIRE 16 -1 (-8200 11150)(-8000 11150);
WIRE 16 -1 (-3250 10050)(-3250 10000);
WIRE 16 -1 (-3250 10000)(-3500 10000);
WIRE 16 -1 (-3500 10000)(-3500 10100);
WIRE 16 -1 (-4050 10000)(-3500 10000);
WIRE 16 -1 (-4050 10100)(-3500 10100);
WIRE 16 -1 (-3550 9000)(-3150 9000);
WIRE 16 -1 (-3550 9100)(-3550 9000);
WIRE 16 -1 (-4050 9000)(-3550 9000);
WIRE 16 -1 (-3150 9100)(-3150 9000);
WIRE 16 -1 (-3550 9100)(-3550 9200);
WIRE 16 -1 (-4050 9100)(-3550 9100);
WIRE 16 -1 (-4050 9200)(-3550 9200);
WIRE 16 -1 (-13100 8050)(-13500 8050);
WIRE 16 -1 (-12450 8050)(-13100 8050);
WIRE 16 -1 (-13100 8050)(-13100 7950);
WIRE 16 -1 (-13500 7800)(-13500 8050);
WIRE 16 -1 (-13500 8050)(-14150 8050);
WIRE 16 -1 (-14150 8150)(-14150 8050);
WIRE 16 -1 (-14150 8050)(-14150 7650);
WIRE 16 -1 (-12450 7950)(-13100 7950);
WIRE 16 -1 (-13100 7800)(-13100 7950);
WIRE 16 -1 (-11750 7800)(-13100 7800);
WIRE 16 -1 (-13100 7650)(-13100 7800);
WIRE 16 -1 (-11750 7800)(-11750 7450);
WIRE 16 -1 (-11750 7450)(-11950 7450);
WIRE 16 -1 (-10900 11850)(-10400 11850);
WIRE 16 -1 (-10900 11850)(-10900 11700);
WIRE 16 -1 (-11450 11850)(-10900 11850);
WIRE 16 -1 (-10100 11850)(-10400 11850);
WIRE 16 -1 (-10400 11850)(-10400 11050);
WIRE 16 -1 (-10400 11050)(-10150 11050);
WIRE 16 -1 (-10400 10250)(-10400 11050);
WIRE 16 -1 (-11450 11850)(-11450 11950);
WIRE 16 -1 (-11450 11750)(-11450 11850);
WIRE 16 -1 (-8000 10250)(-10400 10250);
WIRE 16 -1 (-8950 8000)(-8950 7750);
WIRE 16 -1 (-8350 7750)(-8950 7750);
WIRE 16 -1 (-8950 7650)(-8950 7750);
WIRE 16 -1 (-8100 7750)(-8350 7750);
WIRE 16 -1 (-8350 8000)(-8350 7750);
WIRE 16 -1 (-8100 8350)(-8100 7750);
WIRE 16 -1 (-8000 8350)(-8100 8350);
WIRE 16 -1 (-13500 7000)(-13500 7100);
WIRE 16 -1 (-13500 6900)(-13500 7000);
WIRE 16 -1 (-14150 7000)(-13500 7000);
WIRE 16 -1 (-14150 7400)(-14150 7000);
WIRE 16 -1 (-10900 10600)(-10900 10450);
WIRE 16 -1 (-10900 10400)(-10900 10450);
WIRE 16 -1 (-10900 10450)(-11450 10450);
WIRE 16 -1 (-11450 10450)(-11450 10600);
WIRE 16 -1 (-9000 10650)(-9000 10550);
WIRE 16 -1 (-9000 10500)(-9000 10550);
WIRE 16 -1 (-9500 10550)(-9000 10550);
WIRE 16 -1 (-9500 10650)(-9500 10550);
WIRE 16 -1 (-9000 11450)(-9000 11400);
WIRE 16 -1 (-9000 11350)(-9000 11400);
WIRE 16 -1 (-9000 11400)(-9500 11400);
WIRE 16 -1 (-9500 11450)(-9500 11400);
WIRE 16 -1 (-10900 11450)(-10900 11350);
WIRE 16 -1 (-10900 11300)(-10900 11350);
WIRE 16 -1 (-10900 11350)(-11450 11350);
WIRE 16 -1 (-11450 11500)(-11450 11350);
WIRE 16 -1 (-11700 9000)(-11700 8700);
WIRE 16 -1 (-11700 8700)(-12200 8700);
WIRE 16 -1 (-12200 8800)(-12200 8700);
WIRE 16 -1 (-12200 8650)(-12200 8700);
WIRE 16 -1 (-12100 4000)(-12450 4000);
WIRE 16 -1 (-12450 4000)(-12450 4300);
WIRE 16 -1 (-12450 4000)(-12450 3900);
WIRE 16 -1 (-12450 3900)(-12100 3900);
WIRE 16 -1 (-12450 4600)(-12450 4300);
WIRE 16 -1 (-12750 4300)(-12450 4300);
WIRE 16 -1 (-12550 4600)(-12450 4600);
WIRE 16 -1 (-12100 4600)(-12400 4600);
WIRE 16 -1 (-12400 4700)(-12400 4600);
WIRE 16 -1 (-12400 4600)(-12400 4450);
WIRE 16 -1 (-12400 4450)(-11950 4450);
FORCEPROP 2 LAST SIG_NAME MUX1_SEL
J 0
(-12360 4460);
DISPLAY 1.021277 (-12360 4460);
WIRE 16 -1 (-12400 4200)(-12400 4450);
WIRE 16 -1 (-12100 4700)(-12400 4700);
WIRE 16 -1 (-12550 4700)(-12400 4700);
WIRE 16 -1 (-12100 4200)(-12400 4200);
WIRE 16 -1 (-12400 4200)(-12400 4100);
WIRE 16 -1 (-12400 4100)(-12100 4100);
WIRE 16 -1 (-14400 4000)(-13650 4000);
FORCEPROP 2 LAST SIG_NAME FT_USB_DETECT
J 0
(-14360 4010);
DISPLAY 1.021277 (-14360 4010);
WIRE 16 -1 (-13250 4000)(-13650 4000);
WIRE 16 -1 (-13650 4000)(-13650 3450);
WIRE 16 -1 (-13650 3450)(-13300 3450);
WIRE 16 -1 (-13050 3450)(-11200 3450);
FORCEPROP 2 LAST SIG_NAME FPGA_IO_FT_USBDET_RST_N
J 0
(-12460 3460);
DISPLAY 1.021277 (-12460 3460);
WIRE 16 -1 (-12550 4900)(-7800 4900);
FORCEPROP 2 LAST SIG_NAME FT4232_SPI_CS_N
J 0
(-8860 4910);
DISPLAY 1.021277 (-8860 4910);
WIRE 16 -1 (-10700 7550)(-10700 7650);
WIRE 16 -1 (-10700 7650)(-10700 8450);
WIRE 16 -1 (-10700 7650)(-10600 7650);
WIRE 16 -1 (-10700 8750)(-10700 8450);
WIRE 16 -1 (-10350 8450)(-10700 8450);
WIRE 16 -1 (-8000 8750)(-10700 8750);
WIRE 16 -1 (-11950 7350)(-11250 7350);
FORCEPROP 2 LAST SIG_NAME FTDI_EE_CS
J 0
(-11810 7360);
DISPLAY 1.021277 (-11810 7360);
WIRE 16 -1 (-11250 7350)(-11250 8050);
WIRE 16 -1 (-11250 9150)(-11250 8050);
WIRE 16 -1 (-12200 8050)(-11250 8050);
WIRE 16 -1 (-8000 9150)(-11250 9150);
WIRE 16 273 (-14450 6350)(-50 6350);
WIRE 16 -1 (-12550 5800)(-7800 5800);
FORCEPROP 2 LAST SIG_NAME FT4232_SPI_CLK
J 0
(-8860 5810);
DISPLAY 1.021277 (-8860 5810);
WIRE 16 -1 (-12550 5500)(-7800 5500);
FORCEPROP 2 LAST SIG_NAME FT4232_SPI_MOSI
J 0
(-8860 5510);
DISPLAY 1.021277 (-8860 5510);
WIRE 16 -1 (-5150 8750)(-2900 8750);
FORCEPROP 2 LAST SIG_NAME FT4232_CHD_TX
J 0
(-3810 8760);
DISPLAY 1.021277 (-3810 8760);
WIRE 16 -1 (-2900 8750)(-2750 8750);
WIRE 16 -1 (-2900 8750)(-2900 8550);
WIRE 16 -1 (-2750 8550)(-2900 8550);
WIRE 16 -1 (-2750 8350)(-3000 8350);
FORCEPROP 2 LAST SIG_NAME FT4232_CHD_RX
J 0
(-3810 8660);
DISPLAY 1.021277 (-3810 8660);
WIRE 16 -1 (-3000 8350)(-3000 8650);
WIRE 16 -1 (-3000 8350)(-3000 8150);
WIRE 16 -1 (-2750 8150)(-3000 8150);
WIRE 16 -1 (-3000 8650)(-5150 8650);
WIRE 16 -1 (-5400 8650)(-5800 8650);
WIRE 16 -1 (-5800 8650)(-5800 9000);
WIRE 16 -1 (-5800 8650)(-6800 8650);
FORCEPROP 2 LAST SIG_NAME R_FT4232_CHD_RX
J 0
(-6710 8660);
DISPLAY 1.021277 (-6710 8660);
WIRE 16 -1 (-5800 9000)(-4300 9000);
WIRE 16 -1 (-6800 10450)(-5400 10450);
FORCEPROP 2 LAST SIG_NAME R_FT4232_I2C_SDA_OUT
J 0
(-6710 10460);
DISPLAY 1.021277 (-6710 10460);
WIRE 16 -1 (-6350 10050)(-6800 10050);
WIRE 16 -1 (-5150 11150)(-2900 11150);
FORCEPROP 2 LAST SIG_NAME FT4232_TMS_SPICS_N
J 0
(-3810 11160);
DISPLAY 1.021277 (-3810 11160);
WIRE 16 -1 (-5150 11350)(-2900 11350);
FORCEPROP 2 LAST SIG_NAME FT4232_TDI_MOSI
J 0
(-3810 11360);
DISPLAY 1.021277 (-3810 11360);
WIRE 16 -1 (-5400 8750)(-6800 8750);
FORCEPROP 2 LAST SIG_NAME R_FT4232_CHD_TX
J 0
(-6710 8760);
DISPLAY 1.021277 (-6710 8760);
WIRE 16 -1 (-6800 11350)(-5400 11350);
FORCEPROP 2 LAST SIG_NAME R_FT4232_TDI
J 0
(-6710 11360);
DISPLAY 1.021277 (-6710 11360);
WIRE 16 -1 (-6800 11250)(-5750 11250);
FORCEPROP 2 LAST SIG_NAME R_FT4232_TDO
J 0
(-6710 11260);
DISPLAY 1.021277 (-6710 11260);
WIRE 16 -1 (-5750 11250)(-5750 11600);
WIRE 16 -1 (-5400 11250)(-5750 11250);
WIRE 16 -1 (-5400 11600)(-5750 11600);
WIRE 16 -1 (-6800 11150)(-5400 11150);
FORCEPROP 2 LAST SIG_NAME R_FT4232_TMS
J 0
(-6710 11160);
DISPLAY 1.021277 (-6710 11160);
WIRE 16 -1 (-6800 11050)(-5900 11050);
FORCEPROP 2 LAST SIG_NAME FT4232_MUX1_SEL
J 0
(-6710 11060);
DISPLAY 1.021277 (-6710 11060);
WIRE 16 -1 (-6800 11450)(-5400 11450);
FORCEPROP 2 LAST SIG_NAME R_FT4232_TCK
J 0
(-6710 11460);
DISPLAY 1.021277 (-6710 11460);
WIRE 16 -1 (-5150 11450)(-2900 11450);
FORCEPROP 2 LAST SIG_NAME FT4232_TCK_SCLK
J 0
(-3810 11460);
DISPLAY 1.021277 (-3810 11460);
WIRE 16 -1 (-6800 10950)(-5900 10950);
FORCEPROP 2 LAST SIG_NAME FT4232_MUX2_SEL
J 0
(-6710 10960);
DISPLAY 1.021277 (-6710 10960);
WIRE 16 -1 (-11950 7150)(-11050 7150);
FORCEPROP 2 LAST SIG_NAME FTDI_EE_DAT
J 0
(-11810 7160);
DISPLAY 1.021277 (-11810 7160);
WIRE 16 -1 (-11050 7150)(-11050 8950);
WIRE 16 -1 (-11050 6850)(-11050 7150);
WIRE 16 -1 (-11850 6850)(-11050 6850);
WIRE 16 -1 (-8000 8950)(-11050 8950);
WIRE 16 -1 (-11150 7250)(-11150 7950);
WIRE 16 -1 (-11150 7250)(-11950 7250);
FORCEPROP 2 LAST SIG_NAME FTDI_EE_CLK
J 0
(-11810 7260);
DISPLAY 1.021277 (-11810 7260);
WIRE 16 -1 (-11150 9050)(-11150 7950);
WIRE 16 -1 (-12200 7950)(-11150 7950);
WIRE 16 -1 (-8000 9050)(-11150 9050);
WIRE 16 -1 (-9650 8550)(-8000 8550);
WIRE 16 -1 (-9650 8550)(-9650 8450);
WIRE 16 -1 (-10100 8450)(-9650 8450);
WIRE 16 -1 (-9650 7950)(-9650 8450);
WIRE 16 -1 (-9650 7750)(-9650 7950);
WIRE 16 -1 (-9900 7950)(-9650 7950);
WIRE 16 -1 (-8350 8250)(-8350 9550);
WIRE 16 -1 (-8000 9550)(-8350 9550);
WIRE 16 -1 (-8950 5000)(-7800 5000);
FORCEPROP 2 LAST SIG_NAME FPGA_FLASH_CS_N
J 0
(-8860 5010);
DISPLAY 1.021277 (-8860 5010);
WIRE 16 -1 (-11850 4700)(-10650 4700);
FORCEPROP 2 LAST SIG_NAME FPGA_OUT_MUX1_SEL
J 0
(-11460 4710);
DISPLAY 1.021277 (-11460 4710);
WIRE 16 -1 (-11850 4600)(-10650 4600);
FORCEPROP 2 LAST SIG_NAME FT4232_MUX1_SEL
J 0
(-11460 4610);
DISPLAY 1.021277 (-11460 4610);
WIRE 16 -1 (-2200 4700)(-3450 4700);
FORCEPROP 2 LAST SIG_NAME FPGA_EEPROM_I2C_SCL
J 0
(-3410 4710);
DISPLAY 1.021277 (-3410 4710);
WIRE 16 -1 (-3450 4700)(-3450 4650);
WIRE 16 -1 (-3450 4700)(-3500 4700);
WIRE 16 -1 (-4350 4650)(-3450 4650);
WIRE 16 -1 (-3500 5500)(-2300 5500);
FORCEPROP 2 LAST SIG_NAME FT4232_I2C_SDA
J 0
(-3410 5510);
DISPLAY 1.021277 (-3410 5510);
WIRE 16 -1 (-2200 5500)(-2300 5500);
WIRE 16 -1 (-2300 5500)(-2300 4900);
WIRE 16 -1 (-2300 4900)(-2200 4900);
WIRE 16 -1 (-6800 9550)(-5800 9550);
FORCEPROP 2 LAST SIG_NAME R_FT4232_CHC_RX
J 0
(-6710 9560);
DISPLAY 1.021277 (-6710 9560);
WIRE 16 -1 (-5400 9550)(-5800 9550);
WIRE 16 -1 (-5800 9100)(-5800 9550);
WIRE 16 -1 (-4300 9100)(-5800 9100);
WIRE 16 -1 (-7000 5600)(-6000 5600);
FORCEPROP 2 LAST SIG_NAME FLASH_DQ0_MOSI
J 0
(-6660 5610);
DISPLAY 1.021277 (-6660 5610);
WIRE 16 -1 (-2050 7950)(-950 7950);
FORCEPROP 2 LAST SIG_NAME FPGA_CFG_INIT_N
J 0
(-1810 7960);
DISPLAY 1.021277 (-1810 7960);
WIRE 16 -1 (-950 8750)(-2050 8750);
FORCEPROP 2 LAST SIG_NAME DBG_UART_MAC_RX
J 0
(-1810 8760);
DISPLAY 1.021277 (-1810 8760);
WIRE 16 -1 (-950 8550)(-2050 8550);
FORCEPROP 2 LAST SIG_NAME DBG_UART_GPS_RXD
J 0
(-1810 8560);
DISPLAY 1.021277 (-1810 8560);
WIRE 16 -1 (-950 8350)(-2050 8350);
FORCEPROP 2 LAST SIG_NAME DBG_UART_MAC_TX
J 0
(-1810 8360);
DISPLAY 1.021277 (-1810 8360);
WIRE 16 -1 (-950 8150)(-2050 8150);
FORCEPROP 2 LAST SIG_NAME DBG_UART_GPS_TXD
J 0
(-1810 8160);
DISPLAY 1.021277 (-1810 8160);
WIRE 16 -1 (-10550 10050)(-8200 10050);
FORCEPROP 2 LAST SIG_NAME FT4232_VREGOUT
J 0
(-9010 10060);
DISPLAY 1.021277 (-9010 10060);
WIRE 16 -1 (-10550 11000)(-10550 10050);
WIRE 16 -1 (-8000 10050)(-8200 10050);
WIRE 16 -1 (-8200 10050)(-8200 10750);
WIRE 16 -1 (-8200 10750)(-8000 10750);
WIRE 16 -1 (-8200 10750)(-8200 10850);
WIRE 16 -1 (-10900 11000)(-10550 11000);
WIRE 16 -1 (-10900 11000)(-10900 10850);
WIRE 16 -1 (-11450 11000)(-10900 11000);
WIRE 16 -1 (-8200 10850)(-8000 10850);
WIRE 16 -1 (-8200 10950)(-8200 10850);
WIRE 16 -1 (-8000 10950)(-8200 10950);
WIRE 16 -1 (-11450 10850)(-11450 11000);
WIRE 16 -1 (-10600 9250)(-8950 9250);
FORCEPROP 2 LAST SIG_NAME FT_USB_DETECT
J 0
(-10560 9260);
DISPLAY 1.021277 (-10560 9260);
WIRE 16 -1 (-8950 9250)(-8950 9350);
WIRE 16 -1 (-8950 8250)(-8950 9250);
WIRE 16 -1 (-8700 9350)(-8950 9350);
WIRE 16 -1 (-9000 9350)(-8950 9350);
WIRE 16 -1 (-9000 9500)(-9000 9350);
WIRE 16 -1 (-9450 9350)(-9000 9350);
WIRE 16 -1 (-9450 9500)(-9000 9500);
WIRE 16 -1 (-12100 6850)(-13100 6850);
FORCEPROP 2 LAST SIG_NAME FTDI_EE_DO
J 0
(-13010 6860);
DISPLAY 1.021277 (-13010 6860);
WIRE 16 -1 (-13100 6850)(-13100 7200);
WIRE 16 -1 (-12750 7200)(-13100 7200);
WIRE 16 -1 (-13100 7400)(-13100 7200);
WIRE 16 -1 (-12750 7450)(-12750 7200);
WIRE 16 -1 (-12650 7450)(-12750 7450);
WIRE 16 -1 (-2800 4100)(-2350 4100);
FORCEPROP 2 LAST SIG_NAME MUX3_SEL
J 0
(-2760 4110);
DISPLAY 1.021277 (-2760 4110);
WIRE 16 -1 (-2350 4400)(-2350 4100);
WIRE 16 -1 (-2350 4100)(-2350 3850);
WIRE 16 -1 (-2350 3850)(-2350 3750);
WIRE 16 -1 (-3000 3850)(-2350 3850);
WIRE 16 -1 (-2200 4400)(-2350 4400);
WIRE 16 -1 (-2400 4400)(-2350 4400);
WIRE 16 -1 (-2400 4300)(-2400 4400);
WIRE 16 -1 (-2850 4400)(-2400 4400);
WIRE 16 -1 (-3000 3750)(-2350 3750);
WIRE 16 -1 (-2850 4300)(-2400 4300);
WIRE 16 -1 (-4300 4400)(-3100 4400);
FORCEPROP 2 LAST SIG_NAME FPGA_OUT_MUX3_SEL
J 0
(-4260 4410);
DISPLAY 1.021277 (-4260 4410);
WIRE 16 -1 (-4300 4300)(-3100 4300);
FORCEPROP 2 LAST SIG_NAME FT4232_MUX3_SEL
J 0
(-4260 4310);
DISPLAY 1.021277 (-4260 4310);
WIRE 16 -1 (-3000 3650)(-2300 3650);
WIRE 16 -1 (-2300 4300)(-2300 3650);
WIRE 16 -1 (-2200 4300)(-2300 4300);
WIRE 16 -1 (-14400 5000)(-13350 5000);
FORCEPROP 2 LAST SIG_NAME FT4232_TMS_SPICS_N
J 0
(-14360 5010);
DISPLAY 1.021277 (-14360 5010);
WIRE 16 -1 (-14400 5300)(-13350 5300);
FORCEPROP 2 LAST SIG_NAME FT4232_TDO_MISO
J 0
(-14360 5310);
DISPLAY 1.021277 (-14360 5310);
WIRE 16 -1 (-14400 5600)(-13350 5600);
FORCEPROP 2 LAST SIG_NAME FT4232_TDI_MOSI
J 0
(-14360 5610);
DISPLAY 1.021277 (-14360 5610);
WIRE 16 -1 (-14400 5900)(-13350 5900);
FORCEPROP 2 LAST SIG_NAME FT4232_TCK_SCLK
J 0
(-14360 5910);
DISPLAY 1.021277 (-14360 5910);
WIRE 16 -1 (-3450 5000)(-2200 5000);
FORCEPROP 2 LAST SIG_NAME FPGA_EEPROM_I2C_SDA
J 0
(-3410 5010);
DISPLAY 1.021277 (-3410 5010);
WIRE 16 -1 (-3450 5000)(-3450 4950);
WIRE 16 -1 (-3500 5000)(-3450 5000);
WIRE 16 -1 (-4350 4950)(-3450 4950);
WIRE 16 -1 (-8550 4400)(-8050 4400);
FORCEPROP 2 LAST SIG_NAME MUX2_SEL
J 0
(-8510 4410);
DISPLAY 1.021277 (-8510 4410);
WIRE 16 -1 (-8050 4600)(-8050 4400);
WIRE 16 -1 (-8050 4400)(-8050 4200);
WIRE 16 -1 (-8050 4200)(-8050 4100);
WIRE 16 -1 (-8650 4200)(-8050 4200);
WIRE 16 -1 (-8050 4700)(-8050 4600);
WIRE 16 -1 (-8050 4600)(-8400 4600);
WIRE 16 -1 (-7800 4700)(-8050 4700);
WIRE 16 -1 (-8400 4700)(-8050 4700);
WIRE 16 -1 (-8050 4100)(-8050 3900);
WIRE 16 -1 (-8050 4100)(-8650 4100);
WIRE 16 -1 (-7800 3900)(-8050 3900);
WIRE 16 -1 (-8050 3900)(-8050 3250);
WIRE 16 -1 (-8050 3250)(-7800 3250);
WIRE 16 -1 (-7800 4600)(-7950 4600);
WIRE 16 -1 (-7950 4600)(-7950 4000);
WIRE 16 -1 (-8650 4000)(-7950 4000);
WIRE 16 -1 (-8850 3700)(-7900 3700);
FORCEPROP 2 LAST SIG_NAME FPGA_FLASH_DQ2
J 0
(-8760 3710);
DISPLAY 1.021277 (-8760 3710);
WIRE 16 -1 (-7800 3700)(-7900 3700);
WIRE 16 -1 (-7900 3700)(-7900 3500);
WIRE 16 -1 (-7900 3500)(-7550 3500);
WIRE 16 -1 (-9850 4600)(-8650 4600);
FORCEPROP 2 LAST SIG_NAME FT4232_MUX2_SEL
J 0
(-9810 4610);
DISPLAY 1.021277 (-9810 4610);
WIRE 16 -1 (-4600 9650)(-2900 9650);
FORCEPROP 2 LAST SIG_NAME UART_FT4232_TX_FPGA_RX
J 0
(-4010 9660);
DISPLAY 1.021277 (-4010 9660);
WIRE 16 -1 (-4600 9650)(-4600 9200);
WIRE 16 -1 (-5150 9650)(-4600 9650);
WIRE 16 -1 (-4600 9200)(-4300 9200);
WIRE 16 -1 (-9700 9500)(-10600 9500);
FORCEPROP 2 LAST SIG_NAME XP3R3V_FT_PG
J 0
(-10560 9510);
DISPLAY 1.021277 (-10560 9510);
WIRE 16 -1 (-8000 9850)(-9150 9850);
FORCEPROP 2 LAST SIG_NAME R_FT_USB_DM
J 0
(-8710 9860);
DISPLAY 1.021277 (-8710 9860);
WIRE 16 -1 (-6900 3050)(-6900 2850);
WIRE 16 -1 (-7000 3050)(-6900 3050);
WIRE 16 -1 (-6900 3050)(-6150 3050);
FORCEPROP 2 LAST SIG_NAME FLASH_DQ3
J 0
(-6610 3060);
DISPLAY 1.021277 (-6610 3060);
WIRE 16 -1 (-6900 2850)(-7300 2850);
WIRE 16 -1 (-6900 3700)(-6150 3700);
FORCEPROP 2 LAST SIG_NAME FLASH_DQ2
J 0
(-6610 3710);
DISPLAY 1.021277 (-6610 3710);
WIRE 16 -1 (-7000 3700)(-6900 3700);
WIRE 16 -1 (-6900 3700)(-6900 3500);
WIRE 16 -1 (-6900 3500)(-7300 3500);
WIRE 16 -1 (-6350 10750)(-6800 10750);
WIRE 16 -1 (-6350 10250)(-6800 10250);
WIRE 16 -1 (-6350 10150)(-6800 10150);
WIRE 16 -1 (-8000 9750)(-9150 9750);
FORCEPROP 2 LAST SIG_NAME R_FT_USB_DP
J 0
(-8710 9760);
DISPLAY 1.021277 (-8710 9760);
WIRE 16 -1 (-6800 10550)(-5400 10550);
FORCEPROP 2 LAST SIG_NAME R_FT4232_I2C_SCL
J 0
(-6710 10560);
DISPLAY 1.021277 (-6710 10560);
WIRE 16 -1 (-8400 11850)(-9000 11850);
FORCEPROP 2 LAST SIG_NAME XP3R3V_VPLL
J 0
(-8960 11860);
DISPLAY 1.021277 (-8960 11860);
WIRE 16 -1 (-8400 11850)(-8400 10550);
WIRE 16 -1 (-9000 11850)(-9000 11700);
WIRE 16 -1 (-9500 11850)(-9000 11850);
WIRE 16 -1 (-9700 11850)(-9500 11850);
WIRE 16 -1 (-9500 11850)(-9500 11700);
WIRE 16 -1 (-8400 10550)(-8000 10550);
WIRE 16 -1 (-2200 5200)(-2350 5200);
WIRE 16 -1 (-2350 5200)(-2350 4600);
WIRE 16 -1 (-2350 5200)(-3500 5200);
FORCEPROP 2 LAST SIG_NAME FT4232_I2C_SCL
J 0
(-3410 5210);
DISPLAY 1.021277 (-3410 5210);
WIRE 16 -1 (-2350 4600)(-2200 4600);
WIRE 16 -1 (-5150 9550)(-2900 9550);
FORCEPROP 2 LAST SIG_NAME UART_FT4232_RX_FPGA_TX
J 0
(-4010 9560);
DISPLAY 1.021277 (-4010 9560);
WIRE 16 -1 (-350 5000)(-1400 5000);
FORCEPROP 2 LAST SIG_NAME EEPROM_I2C_SDA
J 0
(-1110 5010);
DISPLAY 1.021277 (-1110 5010);
WIRE 16 -1 (-1400 5300)(-350 5300);
FORCEPROP 2 LAST SIG_NAME PCA9546_I2C_SCL
J 0
(-1110 5310);
DISPLAY 1.021277 (-1110 5310);
WIRE 16 -1 (-6800 10850)(-5900 10850);
FORCEPROP 2 LAST SIG_NAME FT4232_MUX3_SEL
J 0
(-6710 10860);
DISPLAY 1.021277 (-6710 10860);
WIRE 16 -1 (-6800 9650)(-5400 9650);
FORCEPROP 2 LAST SIG_NAME R_FT4232_CHC_TX
J 0
(-6710 9660);
DISPLAY 1.021277 (-6710 9660);
WIRE 16 -1 (-8500 11050)(-8500 10450);
WIRE 16 -1 (-8500 11050)(-9000 11050);
FORCEPROP 2 LAST SIG_NAME XP3R3V_VPHY
J 0
(-9010 11060);
DISPLAY 1.021277 (-9010 11060);
WIRE 16 -1 (-8500 10450)(-8000 10450);
WIRE 16 -1 (-9000 10900)(-9000 11050);
WIRE 16 -1 (-9500 11050)(-9000 11050);
WIRE 16 -1 (-9500 10900)(-9500 11050);
WIRE 16 -1 (-9750 11050)(-9500 11050);
WIRE 16 -1 (-11550 5600)(-12550 5600);
FORCEPROP 2 LAST SIG_NAME FT4232_FPGA_TDI
J 0
(-12310 5610);
DISPLAY 1.021277 (-12310 5610);
WIRE 16 -1 (-12550 5900)(-11550 5900);
FORCEPROP 2 LAST SIG_NAME FT4232_FPGA_TCK
J 0
(-12310 5910);
DISPLAY 1.021277 (-12310 5910);
WIRE 16 -1 (-6350 9850)(-6800 9850);
WIRE 16 -1 (-6350 9950)(-6800 9950);
WIRE 16 -1 (-8450 9350)(-8000 9350);
WIRE 16 -1 (-8850 3050)(-7900 3050);
FORCEPROP 2 LAST SIG_NAME FPGA_FLASH_DQ3
J 0
(-8760 3060);
DISPLAY 1.021277 (-8760 3060);
WIRE 16 -1 (-7800 3050)(-7900 3050);
WIRE 16 -1 (-7900 3050)(-7900 2850);
WIRE 16 -1 (-7900 2850)(-7550 2850);
WIRE 16 -1 (-8950 5600)(-7800 5600);
FORCEPROP 2 LAST SIG_NAME FPGA_FLASH_DQ0_MOSI
J 0
(-8860 5610);
DISPLAY 1.021277 (-8860 5610);
WIRE 16 -1 (-12550 5300)(-11550 5300);
FORCEPROP 2 LAST SIG_NAME FT4232_FPGA_TDO
J 0
(-12310 5310);
DISPLAY 1.021277 (-12310 5310);
WIRE 16 -1 (-10600 9850)(-9400 9850);
FORCEPROP 2 LAST SIG_NAME FT_USB_DM
J 0
(-10510 9860);
DISPLAY 1.021277 (-10510 9860);
WIRE 16 -1 (-11550 5000)(-12550 5000);
FORCEPROP 2 LAST SIG_NAME FT4232_FPGA_TMS
J 0
(-12310 5010);
DISPLAY 1.021277 (-12310 5010);
WIRE 16 -1 (-2200 5600)(-3450 5600);
FORCEPROP 2 LAST SIG_NAME FPGA_PCA9546_I2C_SDA
J 0
(-3410 5610);
DISPLAY 1.021277 (-3410 5610);
WIRE 16 -1 (-3450 5600)(-3450 5550);
WIRE 16 -1 (-3450 5600)(-3500 5600);
WIRE 16 -1 (-4350 5550)(-3450 5550);
WIRE 16 -1 (-8950 5300)(-7800 5300);
FORCEPROP 2 LAST SIG_NAME FPGA_FLASH_DQ1_MISO
J 0
(-8860 5310);
DISPLAY 1.021277 (-8860 5310);
WIRE 16 -1 (-1400 5600)(-350 5600);
FORCEPROP 2 LAST SIG_NAME PCA9546_I2C_SDA
J 0
(-1110 5610);
DISPLAY 1.021277 (-1110 5610);
WIRE 16 -1 (-10600 9750)(-9400 9750);
FORCEPROP 2 LAST SIG_NAME FT_USB_DP
J 0
(-10510 9760);
DISPLAY 1.021277 (-10510 9760);
WIRE 16 -1 (-9850 4700)(-8650 4700);
FORCEPROP 2 LAST SIG_NAME FPGA_OUT_MUX2_SEL
J 0
(-9810 4710);
DISPLAY 1.021277 (-9810 4710);
WIRE 16 -1 (-1400 4700)(-350 4700);
FORCEPROP 2 LAST SIG_NAME EEPROM_I2C_SCL
J 0
(-1110 4710);
DISPLAY 1.021277 (-1110 4710);
WIRE 16 -1 (-12750 10050)(-12450 10050);
WIRE 16 -1 (-12750 9750)(-12400 9750);
FORCEPROP 2 LAST SIG_NAME FT_USB_DM
J 0
(-12660 9760);
DISPLAY 1.021277 (-12660 9760);
WIRE 16 -1 (-12400 9750)(-11950 9750);
WIRE 16 -1 (-12400 9450)(-12400 9750);
WIRE 16 -1 (-12750 9850)(-12000 9850);
FORCEPROP 2 LAST SIG_NAME FT_USB_DP
J 0
(-12660 9860);
DISPLAY 1.021277 (-12660 9860);
WIRE 16 -1 (-12000 9850)(-11950 9850);
WIRE 16 -1 (-12000 9450)(-12000 9850);
WIRE 16 -1 (-14150 10050)(-13850 10050);
WIRE 16 -1 (-14550 9750)(-13850 9750);
FORCEPROP 2 LAST SIG_NAME FT_USB_DM
J 0
(-14510 9760);
DISPLAY 1.021277 (-14510 9760);
WIRE 16 -1 (-14550 9850)(-13850 9850);
FORCEPROP 2 LAST SIG_NAME FT_USB_DP
J 0
(-14510 9860);
DISPLAY 1.021277 (-14510 9860);
WIRE 16 -1 (-12550 5200)(-7800 5200);
FORCEPROP 2 LAST SIG_NAME FT4232_SPI_MISO
J 0
(-8860 5210);
DISPLAY 1.021277 (-8860 5210);
WIRE 16 -1 (-7000 5000)(-6000 5000);
FORCEPROP 2 LAST SIG_NAME FLASH_CS_N
J 0
(-6660 5010);
DISPLAY 1.021277 (-6660 5010);
WIRE 16 -1 (-2200 5300)(-3450 5300);
FORCEPROP 2 LAST SIG_NAME FPGA_PCA9546_I2C_SCL
J 0
(-3410 5310);
DISPLAY 1.021277 (-3410 5310);
WIRE 16 -1 (-3450 5300)(-3450 5250);
WIRE 16 -1 (-3450 5300)(-3500 5300);
WIRE 16 -1 (-4350 5250)(-3450 5250);
WIRE 16 -1 (-7000 5900)(-6000 5900);
FORCEPROP 2 LAST SIG_NAME FLASH_CLK
J 0
(-6660 5910);
DISPLAY 1.021277 (-6660 5910);
WIRE 16 -1 (-7000 5300)(-6000 5300);
FORCEPROP 2 LAST SIG_NAME FLASH_DQ1_MISO
J 0
(-6660 5310);
DISPLAY 1.021277 (-6660 5310);
WIRE 16 -1 (-6800 10350)(-5400 10350);
FORCEPROP 2 LAST SIG_NAME R_FT4232_I2C_SDA_IN
J 0
(-6710 10360);
DISPLAY 1.021277 (-6710 10360);
WIRE 16 -1 (-8950 5900)(-7800 5900);
FORCEPROP 2 LAST SIG_NAME FPGA_FLASH_CLK
J 0
(-8860 5910);
DISPLAY 1.021277 (-8860 5910);
WIRE 16 -1 (-4700 10450)(-2900 10450);
FORCEPROP 2 LAST SIG_NAME FT4232_I2C_SDA
J 0
(-3760 10460);
DISPLAY 1.021277 (-3760 10460);
WIRE 16 -1 (-4700 10450)(-4700 10350);
WIRE 16 -1 (-5150 10450)(-4700 10450);
WIRE 16 -1 (-4700 10350)(-5150 10350);
WIRE 16 -1 (-4700 10350)(-4700 10000);
WIRE 16 -1 (-4300 10000)(-4700 10000);
WIRE 16 -1 (-5150 10550)(-4600 10550);
WIRE 16 -1 (-4600 10550)(-2900 10550);
FORCEPROP 2 LAST SIG_NAME FT4232_I2C_SCL
J 0
(-3760 10560);
DISPLAY 1.021277 (-3760 10560);
WIRE 16 -1 (-4600 10550)(-4600 10100);
WIRE 16 -1 (-4300 10100)(-4600 10100);
WIRE 16 -1 (-5150 11250)(-2900 11250);
FORCEPROP 2 LAST SIG_NAME FT4232_TDO_MISO
J 0
(-3810 11260);
DISPLAY 1.021277 (-3810 11260);
DOT 1 (-5750 11250);
DOT 1 (-11050 7150);
DOT 1 (-14000 9450);
DOT 1 (-12600 9250);
DOT 1 (-2350 4100);
DOT 1 (-8050 4100);
DOT 1 (-8050 4400);
DOT 1 (-9200 4000);
DOT 1 (-8050 4200);
DOT 1 (-12600 9450);
DOT 1 (-12600 9150);
DOT 1 (-14000 8900);
DOT 1 (-14000 9150);
DOT 1 (-14000 9250);
DOT 1 (-12400 4200);
DOT 1 (-12450 4300);
DOT 1 (-13650 2100);
DOT 1 (-13650 2900);
DOT 1 (-13200 2900);
DOT 1 (-12350 2100);
DOT 1 (-12350 2900);
DOT 1 (-11100 2100);
DOT 1 (-11100 2900);
DOT 1 (-4950 4950);
DOT 1 (-4950 5250);
DOT 1 (-4950 5550);
DOT 1 (-3500 10000);
DOT 1 (-4600 10550);
DOT 1 (-4600 9650);
DOT 1 (-4700 10350);
DOT 1 (-8200 11450);
DOT 1 (-8200 11350);
DOT 1 (-8200 11250);
DOT 1 (-8200 10850);
DOT 1 (-8200 10750);
DOT 1 (-8200 10050);
DOT 1 (-2900 8750);
DOT 1 (-3000 8350);
DOT 1 (-3550 9100);
DOT 1 (-3550 9000);
DOT 1 (-5800 8650);
DOT 1 (-6600 7350);
DOT 1 (-6600 7150);
DOT 1 (-6600 7050);
DOT 1 (-6600 6850);
DOT 1 (-6600 6950);
DOT 1 (-6600 6650);
DOT 1 (-6600 6750);
DOT 1 (-9000 11850);
DOT 1 (-9500 11850);
DOT 1 (-9000 11400);
DOT 1 (-9000 11050);
DOT 1 (-9000 10550);
DOT 1 (-9500 11050);
DOT 1 (-10400 11850);
DOT 1 (-10900 11850);
DOT 1 (-11450 11850);
DOT 1 (-10400 11050);
DOT 1 (-10900 11000);
DOT 1 (-11300 9600);
DOT 1 (-8950 9350);
DOT 1 (-9000 9350);
DOT 1 (-8350 7750);
DOT 1 (-8950 7750);
DOT 1 (-9650 8450);
DOT 1 (-9650 7950);
DOT 1 (-9650 7350);
DOT 1 (-10700 8450);
DOT 1 (-11250 8050);
DOT 1 (-11150 7950);
DOT 1 (-12200 8700);
DOT 1 (-13100 7950);
DOT 1 (-13100 8050);
DOT 1 (-13100 7800);
DOT 1 (-13500 8050);
DOT 1 (-14150 8050);
DOT 1 (-13100 7200);
DOT 1 (-13500 7000);
DOT 1 (-2300 5500);
DOT 1 (-2350 5200);
DOT 1 (-3450 5300);
DOT 1 (-3450 5000);
DOT 1 (-3450 4700);
DOT 1 (-2400 4400);
DOT 1 (-2350 4400);
DOT 1 (-2350 3850);
DOT 1 (-3600 3650);
DOT 1 (-3450 5600);
DOT 1 (-4800 2900);
DOT 1 (-4800 2100);
DOT 1 (-3450 2900);
DOT 1 (-3450 2100);
DOT 1 (-8050 4700);
DOT 1 (-8050 4600);
DOT 1 (-8050 3900);
DOT 1 (-11300 4200);
DOT 1 (-12400 4600);
DOT 1 (-11350 3900);
DOT 1 (-13650 4000);
DOT 1 (-12400 4700);
DOT 1 (-7900 3700);
DOT 1 (-6900 3700);
DOT 1 (-6900 3050);
DOT 1 (-8950 9250);
DOT 1 (-10900 10450);
DOT 1 (-10700 7650);
DOT 1 (-10900 11350);
DOT 1 (-7900 3050);
DOT 1 (-4700 10450);
DOT 1 (-6600 7250);
DOT 1 (-14000 10350);
DOT 1 (-12600 10350);
DOT 1 (-11700 9600);
DOT 1 (-12000 9850);
DOT 1 (-12400 9750);
DOT 1 (-5800 9550);
DOT 1 (-11900 2900);
DOT 1 (-12400 4450);
DOT 1 (-12450 4000);
FORCENOTE
JTAG/SPI_MASTER_SEL
(-11600 6150) 0;
DISPLAY LEFT (-11600 6150);
DISPLAY 3.148936 (-11600 6150);
FORCENOTE
5&6 : FT4232_CHD_RX << MAC_TX
(-2650 7150) 0;
DISPLAY LEFT (-2650 7150);
DISPLAY 1.574468 (-2650 7150);
FORCENOTE
1&2 : FT4232_CHD_TX >> MAC_RX
(-2650 7250) 0;
DISPLAY LEFT (-2650 7250);
DISPLAY 1.574468 (-2650 7250);
FORCENOTE
3&4 : FT4232_CHD_TX >> GPS_RX
(-2650 6950) 0;
DISPLAY LEFT (-2650 6950);
DISPLAY 1.574468 (-2650 6950);
FORCENOTE
FT4232 USB TO UART/MPSSE
(-9550 12400) 0;
DISPLAY LEFT (-9550 12400);
DISPLAY 3.936170 (-9550 12400);
FORCENOTE
IN = 0:  COM <> NC.
(-6900 4650) 0;
DISPLAY LEFT (-6900 4650);
DISPLAY 1.021277 (-6900 4650);
FORCENOTE
EN:PULL-DOWN IS ENABLE
(-6900 4800) 0;
DISPLAY LEFT (-6900 4800);
DISPLAY 1.021277 (-6900 4800);
FORCENOTE
- FPGA IN : FT4232 USB DETECT.
(-12400 3200) 0;
DISPLAY LEFT (-12400 3200);
DISPLAY 0.808511 (-12400 3200);
FORCENOTE
RSVD FOR DBG
(-2650 7550) 0;
DISPLAY LEFT (-2650 7550);
DISPLAY 1.574468 (-2650 7550);
FORCENOTE
7&8 : FT4232_CHD_RX << GPS_TX
(-2650 6850) 0;
DISPLAY LEFT (-2650 6850);
DISPLAY 1.574468 (-2650 6850);
FORCENOTE
USB<>JTAG/SPI: FOR FPGA/SPI_FLASH.
(-2450 11250) 0;
DISPLAY LEFT (-2450 11250);
DISPLAY 1.574468 (-2450 11250);
FORCENOTE
I2C_MASTER_SEL
(-2750 6100) 0;
DISPLAY LEFT (-2750 6100);
DISPLAY 3.148936 (-2750 6100);
FORCENOTE
IN = 0:  COM <> NC.
(-14350 4800) 0;
DISPLAY LEFT (-14350 4800);
DISPLAY 1.021277 (-14350 4800);
FORCENOTE
IN = 1:  COM <> N0.
(-1350 4200) 0;
DISPLAY LEFT (-1350 4200);
DISPLAY 1.021277 (-1350 4200);
FORCENOTE
IN = 0:  COM <> NC.
(-1350 4300) 0;
DISPLAY LEFT (-1350 4300);
DISPLAY 1.021277 (-1350 4300);
FORCENOTE
EN:PULL-DOWN IS ENABLE
(-1350 4450) 0;
DISPLAY LEFT (-1350 4450);
DISPLAY 1.021277 (-1350 4450);
FORCENOTE
USB-C CONN
(-13750 10850) 0;
DISPLAY LEFT (-13750 10850);
DISPLAY 1.574468 (-13750 10850);
FORCENOTE
SEL = 0:  A <> B0.
(-8950 3300) 0;
DISPLAY LEFT (-8950 3300);
DISPLAY 1.021277 (-8950 3300);
FORCENOTE
SEL = 1:  A <> B1.
(-8950 3400) 0;
DISPLAY LEFT (-8950 3400);
DISPLAY 1.021277 (-8950 3400);
FORCENOTE
IN = 1:  COM <> N0.
(-14350 4700) 0;
DISPLAY LEFT (-14350 4700);
DISPLAY 1.021277 (-14350 4700);
FORCENOTE
EN:PULL-DOWN IS ENABLE
(-14350 4550) 0;
DISPLAY LEFT (-14350 4550);
DISPLAY 1.021277 (-14350 4550);
FORCENOTE
IN = 1:  COM <> N0.
(-6900 4550) 0;
DISPLAY LEFT (-6900 4550);
DISPLAY 1.021277 (-6900 4550);
FORCENOTE
MP PHASE: DNP J10.
(-2650 7450) 0;
DISPLAY LEFT (-2650 7450);
DISPLAY 1.574468 (-2650 7450);
FORCENOTE
USB<>UART: FPGA UART.
(-2450 9600) 0;
DISPLAY LEFT (-2450 9600);
DISPLAY 1.574468 (-2450 9600);
FORCENOTE
USB<>I2C CONNECT TO I2C_SW & EEPROM.
(-2450 10500) 0;
DISPLAY LEFT (-2450 10500);
DISPLAY 1.574468 (-2450 10500);
FORCENOTE
REFER TO THE FTDI APPLICATION NOTE AN_411 SECTION 8.2.
(-3550 10700) 0;
DISPLAY LEFT (-3550 10700);
FORCENOTE
- FT4232H <> I2C DEVICES, THE FTDI MPSSE ENGINE DOES NOT SUPPORT CLOCK STRETCHING.
(-3650 10800) 0;
DISPLAY LEFT (-3650 10800);
FORCENOTE
NOTE:
(-3950 10800) 0;
DISPLAY LEFT (-3950 10800);
FORCENOTE
USB_DET = 0:MUX = HI-Z.
(-14450 4150) 0;
DISPLAY LEFT (-14450 4150);
DISPLAY 1.021277 (-14450 4150);
FORCENOTE
USB_DET = 1:MUX = ENABLE.
(-14450 4250) 0;
DISPLAY LEFT (-14450 4250);
DISPLAY 1.021277 (-14450 4250);
FORCENOTE
RSVD FOR FUTURE USE.
(-12400 3350) 0;
DISPLAY LEFT (-12400 3350);
DISPLAY 1.021277 (-12400 3350);
FORCENOTE
- FPGA DIR: BI-I/O.
(-12400 3250) 0;
DISPLAY LEFT (-12400 3250);
DISPLAY 0.808511 (-12400 3250);
FORCENOTE
- FPGA OUT-OD: FT4232 RESET.
(-12400 3150) 0;
DISPLAY LEFT (-12400 3150);
DISPLAY 0.808511 (-12400 3150);
QUIT
